(kicad_pcb
	(version 20260206)
	(generator "pcbnew")
	(generator_version "10.0")
	(general
		(thickness 1.6)
		(legacy_teardrops no)
	)
	(paper "A4")
	(layers
		(0 "F.Cu" signal "TOP")
		(2 "B.Cu" signal "BOTTOM")
		(9 "F.Adhes" user "F.Adhesive")
		(11 "B.Adhes" user "B.Adhesive")
		(13 "F.Paste" user "Package Geometry/Pastemask Top")
		(15 "B.Paste" user "Package Geometry/Pastemask Bottom")
		(5 "F.SilkS" user "Ref Des/Silkscreen Top")
		(7 "B.SilkS" user "Ref Des/Silkscreen Bottom")
		(1 "F.Mask" user "Board Geometry/Soldermask Top")
		(3 "B.Mask" user "Board Geometry/Soldermask Bottom")
		(17 "Dwgs.User" user "User.Drawings")
		(19 "Cmts.User" user "User.Comments")
		(21 "Eco1.User" user "User.Eco1")
		(23 "Eco2.User" user "User.Eco2")
		(25 "Edge.Cuts" user "Board Geometry/Outline")
		(27 "Margin" user)
		(31 "F.CrtYd" user "Package Geometry/Place Bound Top")
		(29 "B.CrtYd" user "Package Geometry/Place Bound Bottom")
		(35 "F.Fab" user "Ref Des/Assembly Top")
		(33 "B.Fab" user "Ref Des/Assembly Bottom")
	)
	(setup
		(pad_to_mask_clearance 0)
		(allow_soldermask_bridges_in_footprints no)
		(tenting
			(front yes)
			(back yes)
		)
		(covering
			(front no)
			(back no)
		)
		(plugging
			(front no)
			(back no)
		)
		(capping no)
		(filling no)
		(pcbplotparams
			(layerselection 0x00000000_00000000_55555555_5755f5ff)
			(plot_on_all_layers_selection 0x00000000_00000000_00000000_00000000)
			(disableapertmacros no)
			(usegerberextensions no)
			(usegerberattributes yes)
			(usegerberadvancedattributes yes)
			(creategerberjobfile yes)
			(dashed_line_dash_ratio 12)
			(dashed_line_gap_ratio 3)
			(svgprecision 4)
			(plotframeref no)
			(mode 1)
			(useauxorigin no)
			(pdf_front_fp_property_popups yes)
			(pdf_back_fp_property_popups yes)
			(pdf_metadata yes)
			(pdf_single_document no)
			(dxfpolygonmode yes)
			(dxfimperialunits yes)
			(dxfusepcbnewfont yes)
			(psnegative no)
			(psa4output no)
			(plot_black_and_white yes)
			(sketchpadsonfab no)
			(plotpadnumbers no)
			(hidednponfab no)
			(sketchdnponfab yes)
			(crossoutdnponfab yes)
			(subtractmaskfromsilk no)
			(outputformat 1)
			(mirror no)
			(drillshape 1)
			(scaleselection 1)
			(outputdirectory "")
		)
	)
	(footprint ""
		(layer "F.Cu")
		(at 180.874924 -4.999736)
		(property "Reference" ""
			(at 0 0 0)
			(layer "F.SilkS")
			(hide yes)
			(effects
				(font
					(size 1.27 1.27)
				)
			)
		)
		(property "Value" "*"
			(at -4.0767 1.0668 0)
			(unlocked yes)
			(layer "F.Fab")
			(hide yes)
			(effects
				(font
					(size 1.016 1.016)
					(thickness 0.1524)
				)
			)
		)
		(duplicate_pad_numbers_are_jumpers no)
		(fp_poly
			(pts
				(arc
					(start 3.3147 0)
					(mid -3.3147 0)
					(end 3.3147 0)
				)
			)
			(stroke
				(width 0)
				(type default)
			)
			(fill no)
			(layer "B.CrtYd")
		)
		(fp_poly
			(pts
				(arc
					(start 3.3147 0)
					(mid -3.3147 0)
					(end 3.3147 0)
				)
			)
			(stroke
				(width 0)
				(type default)
			)
			(fill no)
			(layer "F.CrtYd")
		)
		(fp_poly
			(pts
				(arc
					(start 3.3147 0)
					(mid -3.3147 0)
					(end 3.3147 0)
				)
			)
			(stroke
				(width 0)
				(type default)
			)
			(fill no)
			(layer "B.Fab")
		)
		(fp_poly
			(pts
				(arc
					(start 3.3147 0)
					(mid -3.3147 0)
					(end 3.3147 0)
				)
			)
			(stroke
				(width 0)
				(type default)
			)
			(fill no)
			(layer "F.Fab")
		)
		(pad "1" thru_hole circle
			(at 0 0)
			(size 6.0198 6.0198)
			(drill 2.5654)
			(layers "*.Cu" "*.Mask")
			(remove_unused_layers no)
			(net "Net_8")
			(clearance -1.2192)
		)
		(zone
			(layers "F.Cu" "B.Cu")
			(hatch none 0.5)
			(connect_pads
				(clearance 0)
			)
			(min_thickness 0.25)
			(keepout
				(tracks not_allowed)
				(vias allowed)
				(pads allowed)
				(copperpour not_allowed)
				(footprints allowed)
			)
			(placement
				(enabled no)
				(sheetname "")
			)
			(fill
				(thermal_gap 0.5)
				(thermal_bridge_width 0.5)
				(island_removal_mode 0)
			)
			(polygon
				(pts
					(arc
						(start 183.884824 -4.999736)
						(mid 177.865024 -4.999736)
						(end 183.884824 -4.999736)
					)
				)
			)
		)
	)
	(footprint ""
		(layer "F.Cu")
		(at 171.349924 -14.99997)
		(property "Reference" "LED6"
			(at 0 0 0)
			(layer "F.SilkS")
			(hide yes)
			(effects
				(font
					(size 1.27 1.27)
				)
			)
		)
		(property "Value" "LED-BY-19-GP"
			(at -2.132076 1.414018 0)
			(unlocked yes)
			(layer "F.Fab")
			(hide yes)
			(effects
				(font
					(size 1.016 1.016)
					(thickness 0.1524)
				)
			)
		)
		(property "Device Type" "LED-1615-4PH26"
			(at -2.132076 -0.109982 0)
			(unlocked yes)
			(layer "F.Fab")
			(hide yes)
			(effects
				(font
					(size 1.016 1.016)
					(thickness 0.1524)
				)
			)
		)
		(duplicate_pad_numbers_are_jumpers no)
		(fp_line
			(start -1.2954 0.254)
			(end -1.2954 1.6002)
			(stroke
				(width 0.508)
				(type default)
			)
			(layer "F.SilkS")
		)
		(fp_line
			(start -1.2954 1.6002)
			(end 1.2954 1.6002)
			(stroke
				(width 0.508)
				(type default)
			)
			(layer "F.SilkS")
		)
		(fp_line
			(start -1.1176 -1.4224)
			(end 1.1176 -1.4224)
			(stroke
				(width 0.1524)
				(type default)
			)
			(layer "F.SilkS")
		)
		(fp_line
			(start -1.1176 1.4224)
			(end -1.1176 -1.4224)
			(stroke
				(width 0.1524)
				(type default)
			)
			(layer "F.SilkS")
		)
		(fp_line
			(start 1.1176 -1.4224)
			(end 1.1176 1.4224)
			(stroke
				(width 0.1524)
				(type default)
			)
			(layer "F.SilkS")
		)
		(fp_line
			(start 1.1176 1.4224)
			(end -1.1176 1.4224)
			(stroke
				(width 0.1524)
				(type default)
			)
			(layer "F.SilkS")
		)
		(fp_line
			(start 1.2954 1.6002)
			(end 1.2954 0.254)
			(stroke
				(width 0.508)
				(type default)
			)
			(layer "F.SilkS")
		)
		(fp_rect
			(start -0.7493 0.8001)
			(end 0.7493 -0.8001)
			(stroke
				(width 0)
				(type default)
			)
			(fill no)
			(layer "F.CrtYd")
		)
		(fp_poly
			(pts
				(xy -1.3716 1.6764) (xy -1.3716 -1.6764) (xy 1.3716 -1.6764) (xy 1.3716 0.0635) (xy 0.7493 0.0635)
				(xy 0.7493 -0.8001) (xy -0.7493 -0.8001) (xy -0.7493 0.8001) (xy 0.7493 0.8001) (xy 0.7493 0.0762)
				(xy 1.3716 0.0762) (xy 1.3716 1.6764)
			)
			(stroke
				(width 0)
				(type default)
			)
			(fill no)
			(layer "F.CrtYd")
		)
		(fp_rect
			(start -1.3716 1.6764)
			(end 1.3716 -1.6764)
			(stroke
				(width 0)
				(type default)
			)
			(fill no)
			(layer "F.Fab")
		)
		(pad "1" smd rect
			(at 0.50038 -0.73025)
			(size 0.7112 0.8636)
			(layers "F.Cu" "F.Mask" "F.Paste")
			(net "DRV_ACT_29_35")
		)
		(pad "2" smd rect
			(at -0.50038 -0.73025)
			(size 0.7112 0.8636)
			(layers "F.Cu" "F.Mask" "F.Paste")
			(net "FLT_HDD29_35")
		)
		(pad "3" smd rect
			(at 0.50038 0.73025)
			(size 0.7112 0.8636)
			(layers "F.Cu" "F.Mask" "F.Paste")
			(net "DRV_ACT_29_35_N")
		)
		(pad "4" smd rect
			(at -0.50038 0.73025)
			(size 0.7112 0.8636)
			(layers "F.Cu" "F.Mask" "F.Paste")
			(net "FLT_HDD29_35_N")
		)
	)
	(footprint ""
		(layer "F.Cu")
		(at 108.249974 -14.99997)
		(property "Reference" "LED4"
			(at 0 0 0)
			(layer "F.SilkS")
			(hide yes)
			(effects
				(font
					(size 1.27 1.27)
				)
			)
		)
		(property "Value" "LED-BY-19-GP"
			(at -2.132076 1.414018 0)
			(unlocked yes)
			(layer "F.Fab")
			(hide yes)
			(effects
				(font
					(size 1.016 1.016)
					(thickness 0.1524)
				)
			)
		)
		(property "Device Type" "LED-1615-4PH26"
			(at -2.132076 -0.109982 0)
			(unlocked yes)
			(layer "F.Fab")
			(hide yes)
			(effects
				(font
					(size 1.016 1.016)
					(thickness 0.1524)
				)
			)
		)
		(duplicate_pad_numbers_are_jumpers no)
		(fp_line
			(start -1.2954 0.254)
			(end -1.2954 1.6002)
			(stroke
				(width 0.508)
				(type default)
			)
			(layer "F.SilkS")
		)
		(fp_line
			(start -1.2954 1.6002)
			(end 1.2954 1.6002)
			(stroke
				(width 0.508)
				(type default)
			)
			(layer "F.SilkS")
		)
		(fp_line
			(start -1.1176 -1.4224)
			(end 1.1176 -1.4224)
			(stroke
				(width 0.1524)
				(type default)
			)
			(layer "F.SilkS")
		)
		(fp_line
			(start -1.1176 1.4224)
			(end -1.1176 -1.4224)
			(stroke
				(width 0.1524)
				(type default)
			)
			(layer "F.SilkS")
		)
		(fp_line
			(start 1.1176 -1.4224)
			(end 1.1176 1.4224)
			(stroke
				(width 0.1524)
				(type default)
			)
			(layer "F.SilkS")
		)
		(fp_line
			(start 1.1176 1.4224)
			(end -1.1176 1.4224)
			(stroke
				(width 0.1524)
				(type default)
			)
			(layer "F.SilkS")
		)
		(fp_line
			(start 1.2954 1.6002)
			(end 1.2954 0.254)
			(stroke
				(width 0.508)
				(type default)
			)
			(layer "F.SilkS")
		)
		(fp_rect
			(start -0.7493 0.8001)
			(end 0.7493 -0.8001)
			(stroke
				(width 0)
				(type default)
			)
			(fill no)
			(layer "F.CrtYd")
		)
		(fp_poly
			(pts
				(xy -1.3716 1.6764) (xy -1.3716 -1.6764) (xy 1.3716 -1.6764) (xy 1.3716 0.0635) (xy 0.7493 0.0635)
				(xy 0.7493 -0.8001) (xy -0.7493 -0.8001) (xy -0.7493 0.8001) (xy 0.7493 0.8001) (xy 0.7493 0.0762)
				(xy 1.3716 0.0762) (xy 1.3716 1.6764)
			)
			(stroke
				(width 0)
				(type default)
			)
			(fill no)
			(layer "F.CrtYd")
		)
		(fp_rect
			(start -1.3716 1.6764)
			(end 1.3716 -1.6764)
			(stroke
				(width 0)
				(type default)
			)
			(fill no)
			(layer "F.Fab")
		)
		(pad "1" smd rect
			(at 0.50038 -0.73025)
			(size 0.7112 0.8636)
			(layers "F.Cu" "F.Mask" "F.Paste")
			(net "DRV_ACT_27_33")
		)
		(pad "2" smd rect
			(at -0.50038 -0.73025)
			(size 0.7112 0.8636)
			(layers "F.Cu" "F.Mask" "F.Paste")
			(net "FLT_HDD27_33")
		)
		(pad "3" smd rect
			(at 0.50038 0.73025)
			(size 0.7112 0.8636)
			(layers "F.Cu" "F.Mask" "F.Paste")
			(net "DRV_ACT_27_33_N")
		)
		(pad "4" smd rect
			(at -0.50038 0.73025)
			(size 0.7112 0.8636)
			(layers "F.Cu" "F.Mask" "F.Paste")
			(net "FLT_HDD27_33_N")
		)
	)
	(footprint ""
		(layer "F.Cu")
		(at 76.700126 -14.99997)
		(property "Reference" "LED3"
			(at 0 0 0)
			(layer "F.SilkS")
			(hide yes)
			(effects
				(font
					(size 1.27 1.27)
				)
			)
		)
		(property "Value" "LED-BY-19-GP"
			(at -2.132076 1.414018 0)
			(unlocked yes)
			(layer "F.Fab")
			(hide yes)
			(effects
				(font
					(size 1.016 1.016)
					(thickness 0.1524)
				)
			)
		)
		(property "Device Type" "LED-1615-4PH26"
			(at -2.132076 -0.109982 0)
			(unlocked yes)
			(layer "F.Fab")
			(hide yes)
			(effects
				(font
					(size 1.016 1.016)
					(thickness 0.1524)
				)
			)
		)
		(duplicate_pad_numbers_are_jumpers no)
		(fp_line
			(start -1.2954 0.254)
			(end -1.2954 1.6002)
			(stroke
				(width 0.508)
				(type default)
			)
			(layer "F.SilkS")
		)
		(fp_line
			(start -1.2954 1.6002)
			(end 1.2954 1.6002)
			(stroke
				(width 0.508)
				(type default)
			)
			(layer "F.SilkS")
		)
		(fp_line
			(start -1.1176 -1.4224)
			(end 1.1176 -1.4224)
			(stroke
				(width 0.1524)
				(type default)
			)
			(layer "F.SilkS")
		)
		(fp_line
			(start -1.1176 1.4224)
			(end -1.1176 -1.4224)
			(stroke
				(width 0.1524)
				(type default)
			)
			(layer "F.SilkS")
		)
		(fp_line
			(start 1.1176 -1.4224)
			(end 1.1176 1.4224)
			(stroke
				(width 0.1524)
				(type default)
			)
			(layer "F.SilkS")
		)
		(fp_line
			(start 1.1176 1.4224)
			(end -1.1176 1.4224)
			(stroke
				(width 0.1524)
				(type default)
			)
			(layer "F.SilkS")
		)
		(fp_line
			(start 1.2954 1.6002)
			(end 1.2954 0.254)
			(stroke
				(width 0.508)
				(type default)
			)
			(layer "F.SilkS")
		)
		(fp_rect
			(start -0.7493 0.8001)
			(end 0.7493 -0.8001)
			(stroke
				(width 0)
				(type default)
			)
			(fill no)
			(layer "F.CrtYd")
		)
		(fp_poly
			(pts
				(xy -1.3716 1.6764) (xy -1.3716 -1.6764) (xy 1.3716 -1.6764) (xy 1.3716 0.0635) (xy 0.7493 0.0635)
				(xy 0.7493 -0.8001) (xy -0.7493 -0.8001) (xy -0.7493 0.8001) (xy 0.7493 0.8001) (xy 0.7493 0.0762)
				(xy 1.3716 0.0762) (xy 1.3716 1.6764)
			)
			(stroke
				(width 0)
				(type default)
			)
			(fill no)
			(layer "F.CrtYd")
		)
		(fp_rect
			(start -1.3716 1.6764)
			(end 1.3716 -1.6764)
			(stroke
				(width 0)
				(type default)
			)
			(fill no)
			(layer "F.Fab")
		)
		(pad "1" smd rect
			(at 0.50038 -0.73025)
			(size 0.7112 0.8636)
			(layers "F.Cu" "F.Mask" "F.Paste")
			(net "DRV_ACT_26_32")
		)
		(pad "2" smd rect
			(at -0.50038 -0.73025)
			(size 0.7112 0.8636)
			(layers "F.Cu" "F.Mask" "F.Paste")
			(net "FLT_HDD26_32")
		)
		(pad "3" smd rect
			(at 0.50038 0.73025)
			(size 0.7112 0.8636)
			(layers "F.Cu" "F.Mask" "F.Paste")
			(net "DRV_ACT_26_32_N")
		)
		(pad "4" smd rect
			(at -0.50038 0.73025)
			(size 0.7112 0.8636)
			(layers "F.Cu" "F.Mask" "F.Paste")
			(net "FLT_HDD26_32_N")
		)
	)
	(footprint ""
		(layer "F.Cu")
		(at 4.12496 -4.999736)
		(property "Reference" ""
			(at 0 0 0)
			(layer "F.SilkS")
			(hide yes)
			(effects
				(font
					(size 1.27 1.27)
				)
			)
		)
		(property "Value" "*"
			(at -4.0767 1.0668 0)
			(unlocked yes)
			(layer "F.Fab")
			(hide yes)
			(effects
				(font
					(size 1.016 1.016)
					(thickness 0.1524)
				)
			)
		)
		(duplicate_pad_numbers_are_jumpers no)
		(fp_poly
			(pts
				(arc
					(start 3.3147 0)
					(mid -3.3147 0)
					(end 3.3147 0)
				)
			)
			(stroke
				(width 0)
				(type default)
			)
			(fill no)
			(layer "B.CrtYd")
		)
		(fp_poly
			(pts
				(arc
					(start 3.3147 0)
					(mid -3.3147 0)
					(end 3.3147 0)
				)
			)
			(stroke
				(width 0)
				(type default)
			)
			(fill no)
			(layer "F.CrtYd")
		)
		(fp_poly
			(pts
				(arc
					(start 3.3147 0)
					(mid -3.3147 0)
					(end 3.3147 0)
				)
			)
			(stroke
				(width 0)
				(type default)
			)
			(fill no)
			(layer "B.Fab")
		)
		(fp_poly
			(pts
				(arc
					(start 3.3147 0)
					(mid -3.3147 0)
					(end 3.3147 0)
				)
			)
			(stroke
				(width 0)
				(type default)
			)
			(fill no)
			(layer "F.Fab")
		)
		(pad "1" thru_hole circle
			(at 0 0)
			(size 6.0198 6.0198)
			(drill 2.5654)
			(layers "*.Cu" "*.Mask")
			(remove_unused_layers no)
			(net "Net_5")
			(clearance -1.2192)
		)
		(zone
			(layers "F.Cu" "B.Cu")
			(hatch none 0.5)
			(connect_pads
				(clearance 0)
			)
			(min_thickness 0.25)
			(keepout
				(tracks not_allowed)
				(vias allowed)
				(pads allowed)
				(copperpour not_allowed)
				(footprints allowed)
			)
			(placement
				(enabled no)
				(sheetname "")
			)
			(fill
				(thermal_gap 0.5)
				(thermal_bridge_width 0.5)
				(island_removal_mode 0)
			)
			(polygon
				(pts
					(arc
						(start 7.13486 -4.999736)
						(mid 1.11506 -4.999736)
						(end 7.13486 -4.999736)
					)
				)
			)
		)
	)
	(footprint ""
		(layer "F.Cu")
		(at 76.699872 -4.99999)
		(property "Reference" ""
			(at 0 0 0)
			(layer "F.SilkS")
			(hide yes)
			(effects
				(font
					(size 1.27 1.27)
				)
			)
		)
		(property "Value" "*"
			(at -4.0767 1.0668 0)
			(unlocked yes)
			(layer "F.Fab")
			(hide yes)
			(effects
				(font
					(size 1.016 1.016)
					(thickness 0.1524)
				)
			)
		)
		(duplicate_pad_numbers_are_jumpers no)
		(fp_poly
			(pts
				(arc
					(start 3.3147 0)
					(mid -3.3147 0)
					(end 3.3147 0)
				)
			)
			(stroke
				(width 0)
				(type default)
			)
			(fill no)
			(layer "B.CrtYd")
		)
		(fp_poly
			(pts
				(arc
					(start 3.3147 0)
					(mid -3.3147 0)
					(end 3.3147 0)
				)
			)
			(stroke
				(width 0)
				(type default)
			)
			(fill no)
			(layer "F.CrtYd")
		)
		(fp_poly
			(pts
				(arc
					(start 3.3147 0)
					(mid -3.3147 0)
					(end 3.3147 0)
				)
			)
			(stroke
				(width 0)
				(type default)
			)
			(fill no)
			(layer "B.Fab")
		)
		(fp_poly
			(pts
				(arc
					(start 3.3147 0)
					(mid -3.3147 0)
					(end 3.3147 0)
				)
			)
			(stroke
				(width 0)
				(type default)
			)
			(fill no)
			(layer "F.Fab")
		)
		(pad "1" thru_hole circle
			(at 0 0)
			(size 6.0198 6.0198)
			(drill 2.5654)
			(layers "*.Cu" "*.Mask")
			(remove_unused_layers no)
			(net "Net_6")
			(clearance -1.2192)
		)
		(zone
			(layers "F.Cu" "B.Cu")
			(hatch none 0.5)
			(connect_pads
				(clearance 0)
			)
			(min_thickness 0.25)
			(keepout
				(tracks not_allowed)
				(vias allowed)
				(pads allowed)
				(copperpour not_allowed)
				(footprints allowed)
			)
			(placement
				(enabled no)
				(sheetname "")
			)
			(fill
				(thermal_gap 0.5)
				(thermal_bridge_width 0.5)
				(island_removal_mode 0)
			)
			(polygon
				(pts
					(arc
						(start 79.709772 -4.99999)
						(mid 73.689972 -4.99999)
						(end 79.709772 -4.99999)
					)
				)
			)
		)
	)
	(footprint ""
		(layer "F.Cu")
		(at 13.599922 -14.99997)
		(property "Reference" "LED1"
			(at 0 0 0)
			(layer "F.SilkS")
			(hide yes)
			(effects
				(font
					(size 1.27 1.27)
				)
			)
		)
		(property "Value" "LED-BY-19-GP"
			(at -2.132076 1.414018 0)
			(unlocked yes)
			(layer "F.Fab")
			(hide yes)
			(effects
				(font
					(size 1.016 1.016)
					(thickness 0.1524)
				)
			)
		)
		(property "Device Type" "LED-1615-4PH26"
			(at -2.132076 -0.109982 0)
			(unlocked yes)
			(layer "F.Fab")
			(hide yes)
			(effects
				(font
					(size 1.016 1.016)
					(thickness 0.1524)
				)
			)
		)
		(duplicate_pad_numbers_are_jumpers no)
		(fp_line
			(start -1.2954 0.254)
			(end -1.2954 1.6002)
			(stroke
				(width 0.508)
				(type default)
			)
			(layer "F.SilkS")
		)
		(fp_line
			(start -1.2954 1.6002)
			(end 1.2954 1.6002)
			(stroke
				(width 0.508)
				(type default)
			)
			(layer "F.SilkS")
		)
		(fp_line
			(start -1.1176 -1.4224)
			(end 1.1176 -1.4224)
			(stroke
				(width 0.1524)
				(type default)
			)
			(layer "F.SilkS")
		)
		(fp_line
			(start -1.1176 1.4224)
			(end -1.1176 -1.4224)
			(stroke
				(width 0.1524)
				(type default)
			)
			(layer "F.SilkS")
		)
		(fp_line
			(start 1.1176 -1.4224)
			(end 1.1176 1.4224)
			(stroke
				(width 0.1524)
				(type default)
			)
			(layer "F.SilkS")
		)
		(fp_line
			(start 1.1176 1.4224)
			(end -1.1176 1.4224)
			(stroke
				(width 0.1524)
				(type default)
			)
			(layer "F.SilkS")
		)
		(fp_line
			(start 1.2954 1.6002)
			(end 1.2954 0.254)
			(stroke
				(width 0.508)
				(type default)
			)
			(layer "F.SilkS")
		)
		(fp_rect
			(start -0.7493 0.8001)
			(end 0.7493 -0.8001)
			(stroke
				(width 0)
				(type default)
			)
			(fill no)
			(layer "F.CrtYd")
		)
		(fp_poly
			(pts
				(xy -1.3716 1.6764) (xy -1.3716 -1.6764) (xy 1.3716 -1.6764) (xy 1.3716 0.0635) (xy 0.7493 0.0635)
				(xy 0.7493 -0.8001) (xy -0.7493 -0.8001) (xy -0.7493 0.8001) (xy 0.7493 0.8001) (xy 0.7493 0.0762)
				(xy 1.3716 0.0762) (xy 1.3716 1.6764)
			)
			(stroke
				(width 0)
				(type default)
			)
			(fill no)
			(layer "F.CrtYd")
		)
		(fp_rect
			(start -1.3716 1.6764)
			(end 1.3716 -1.6764)
			(stroke
				(width 0)
				(type default)
			)
			(fill no)
			(layer "F.Fab")
		)
		(pad "1" smd rect
			(at 0.50038 -0.73025)
			(size 0.7112 0.8636)
			(layers "F.Cu" "F.Mask" "F.Paste")
			(net "DRV_ACT_24_30")
		)
		(pad "2" smd rect
			(at -0.50038 -0.73025)
			(size 0.7112 0.8636)
			(layers "F.Cu" "F.Mask" "F.Paste")
			(net "FLT_HDD24_30")
		)
		(pad "3" smd rect
			(at 0.50038 0.73025)
			(size 0.7112 0.8636)
			(layers "F.Cu" "F.Mask" "F.Paste")
			(net "DRV_ACT_24_30_N")
		)
		(pad "4" smd rect
			(at -0.50038 0.73025)
			(size 0.7112 0.8636)
			(layers "F.Cu" "F.Mask" "F.Paste")
			(net "FLT_HDD24_30_N")
		)
	)
	(footprint ""
		(layer "F.Cu")
		(at 124.124974 -4.999736)
		(property "Reference" ""
			(at 0 0 0)
			(layer "F.SilkS")
			(hide yes)
			(effects
				(font
					(size 1.27 1.27)
				)
			)
		)
		(property "Value" "*"
			(at -4.0767 1.0668 0)
			(unlocked yes)
			(layer "F.Fab")
			(hide yes)
			(effects
				(font
					(size 1.016 1.016)
					(thickness 0.1524)
				)
			)
		)
		(duplicate_pad_numbers_are_jumpers no)
		(fp_poly
			(pts
				(arc
					(start 3.3147 0)
					(mid -3.3147 0)
					(end 3.3147 0)
				)
			)
			(stroke
				(width 0)
				(type default)
			)
			(fill no)
			(layer "B.CrtYd")
		)
		(fp_poly
			(pts
				(arc
					(start 3.3147 0)
					(mid -3.3147 0)
					(end 3.3147 0)
				)
			)
			(stroke
				(width 0)
				(type default)
			)
			(fill no)
			(layer "F.CrtYd")
		)
		(fp_poly
			(pts
				(arc
					(start 3.3147 0)
					(mid -3.3147 0)
					(end 3.3147 0)
				)
			)
			(stroke
				(width 0)
				(type default)
			)
			(fill no)
			(layer "B.Fab")
		)
		(fp_poly
			(pts
				(arc
					(start 3.3147 0)
					(mid -3.3147 0)
					(end 3.3147 0)
				)
			)
			(stroke
				(width 0)
				(type default)
			)
			(fill no)
			(layer "F.Fab")
		)
		(pad "1" thru_hole circle
			(at 0 0)
			(size 6.0198 6.0198)
			(drill 2.5654)
			(layers "*.Cu" "*.Mask")
			(remove_unused_layers no)
			(net "Net_7")
			(clearance -1.2192)
		)
		(zone
			(layers "F.Cu" "B.Cu")
			(hatch none 0.5)
			(connect_pads
				(clearance 0)
			)
			(min_thickness 0.25)
			(keepout
				(tracks not_allowed)
				(vias allowed)
				(pads allowed)
				(copperpour not_allowed)
				(footprints allowed)
			)
			(placement
				(enabled no)
				(sheetname "")
			)
			(fill
				(thermal_gap 0.5)
				(thermal_bridge_width 0.5)
				(island_removal_mode 0)
			)
			(polygon
				(pts
					(arc
						(start 127.134874 -4.999736)
						(mid 121.115074 -4.999736)
						(end 127.134874 -4.999736)
					)
				)
			)
		)
	)
	(footprint ""
		(layer "F.Cu")
		(at 45.150024 -14.99997)
		(property "Reference" "LED2"
			(at 0 0 0)
			(layer "F.SilkS")
			(hide yes)
			(effects
				(font
					(size 1.27 1.27)
				)
			)
		)
		(property "Value" "LED-BY-19-GP"
			(at -2.132076 1.414018 0)
			(unlocked yes)
			(layer "F.Fab")
			(hide yes)
			(effects
				(font
					(size 1.016 1.016)
					(thickness 0.1524)
				)
			)
		)
		(property "Device Type" "LED-1615-4PH26"
			(at -2.132076 -0.109982 0)
			(unlocked yes)
			(layer "F.Fab")
			(hide yes)
			(effects
				(font
					(size 1.016 1.016)
					(thickness 0.1524)
				)
			)
		)
		(duplicate_pad_numbers_are_jumpers no)
		(fp_line
			(start -1.2954 0.254)
			(end -1.2954 1.6002)
			(stroke
				(width 0.508)
				(type default)
			)
			(layer "F.SilkS")
		)
		(fp_line
			(start -1.2954 1.6002)
			(end 1.2954 1.6002)
			(stroke
				(width 0.508)
				(type default)
			)
			(layer "F.SilkS")
		)
		(fp_line
			(start -1.1176 -1.4224)
			(end 1.1176 -1.4224)
			(stroke
				(width 0.1524)
				(type default)
			)
			(layer "F.SilkS")
		)
		(fp_line
			(start -1.1176 1.4224)
			(end -1.1176 -1.4224)
			(stroke
				(width 0.1524)
				(type default)
			)
			(layer "F.SilkS")
		)
		(fp_line
			(start 1.1176 -1.4224)
			(end 1.1176 1.4224)
			(stroke
				(width 0.1524)
				(type default)
			)
			(layer "F.SilkS")
		)
		(fp_line
			(start 1.1176 1.4224)
			(end -1.1176 1.4224)
			(stroke
				(width 0.1524)
				(type default)
			)
			(layer "F.SilkS")
		)
		(fp_line
			(start 1.2954 1.6002)
			(end 1.2954 0.254)
			(stroke
				(width 0.508)
				(type default)
			)
			(layer "F.SilkS")
		)
		(fp_rect
			(start -0.7493 0.8001)
			(end 0.7493 -0.8001)
			(stroke
				(width 0)
				(type default)
			)
			(fill no)
			(layer "F.CrtYd")
		)
		(fp_poly
			(pts
				(xy -1.3716 1.6764) (xy -1.3716 -1.6764) (xy 1.3716 -1.6764) (xy 1.3716 0.0635) (xy 0.7493 0.0635)
				(xy 0.7493 -0.8001) (xy -0.7493 -0.8001) (xy -0.7493 0.8001) (xy 0.7493 0.8001) (xy 0.7493 0.0762)
				(xy 1.3716 0.0762) (xy 1.3716 1.6764)
			)
			(stroke
				(width 0)
				(type default)
			)
			(fill no)
			(layer "F.CrtYd")
		)
		(fp_rect
			(start -1.3716 1.6764)
			(end 1.3716 -1.6764)
			(stroke
				(width 0)
				(type default)
			)
			(fill no)
			(layer "F.Fab")
		)
		(pad "1" smd rect
			(at 0.50038 -0.73025)
			(size 0.7112 0.8636)
			(layers "F.Cu" "F.Mask" "F.Paste")
			(net "DRV_ACT_25_31")
		)
		(pad "2" smd rect
			(at -0.50038 -0.73025)
			(size 0.7112 0.8636)
			(layers "F.Cu" "F.Mask" "F.Paste")
			(net "FLT_HDD25_31")
		)
		(pad "3" smd rect
			(at 0.50038 0.73025)
			(size 0.7112 0.8636)
			(layers "F.Cu" "F.Mask" "F.Paste")
			(net "DRV_ACT_25_31_N")
		)
		(pad "4" smd rect
			(at -0.50038 0.73025)
			(size 0.7112 0.8636)
			(layers "F.Cu" "F.Mask" "F.Paste")
			(net "FLT_HDD25_31_N")
		)
	)
	(footprint ""
		(layer "F.Cu")
		(at 139.800076 -14.99997)
		(property "Reference" "LED5"
			(at 0 0 0)
			(layer "F.SilkS")
			(hide yes)
			(effects
				(font
					(size 1.27 1.27)
				)
			)
		)
		(property "Value" "LED-BY-19-GP"
			(at -2.132076 1.414018 0)
			(unlocked yes)
			(layer "F.Fab")
			(hide yes)
			(effects
				(font
					(size 1.016 1.016)
					(thickness 0.1524)
				)
			)
		)
		(property "Device Type" "LED-1615-4PH26"
			(at -2.132076 -0.109982 0)
			(unlocked yes)
			(layer "F.Fab")
			(hide yes)
			(effects
				(font
					(size 1.016 1.016)
					(thickness 0.1524)
				)
			)
		)
		(duplicate_pad_numbers_are_jumpers no)
		(fp_line
			(start -1.2954 0.254)
			(end -1.2954 1.6002)
			(stroke
				(width 0.508)
				(type default)
			)
			(layer "F.SilkS")
		)
		(fp_line
			(start -1.2954 1.6002)
			(end 1.2954 1.6002)
			(stroke
				(width 0.508)
				(type default)
			)
			(layer "F.SilkS")
		)
		(fp_line
			(start -1.1176 -1.4224)
			(end 1.1176 -1.4224)
			(stroke
				(width 0.1524)
				(type default)
			)
			(layer "F.SilkS")
		)
		(fp_line
			(start -1.1176 1.4224)
			(end -1.1176 -1.4224)
			(stroke
				(width 0.1524)
				(type default)
			)
			(layer "F.SilkS")
		)
		(fp_line
			(start 1.1176 -1.4224)
			(end 1.1176 1.4224)
			(stroke
				(width 0.1524)
				(type default)
			)
			(layer "F.SilkS")
		)
		(fp_line
			(start 1.1176 1.4224)
			(end -1.1176 1.4224)
			(stroke
				(width 0.1524)
				(type default)
			)
			(layer "F.SilkS")
		)
		(fp_line
			(start 1.2954 1.6002)
			(end 1.2954 0.254)
			(stroke
				(width 0.508)
				(type default)
			)
			(layer "F.SilkS")
		)
		(fp_rect
			(start -0.7493 0.8001)
			(end 0.7493 -0.8001)
			(stroke
				(width 0)
				(type default)
			)
			(fill no)
			(layer "F.CrtYd")
		)
		(fp_poly
			(pts
				(xy -1.3716 1.6764) (xy -1.3716 -1.6764) (xy 1.3716 -1.6764) (xy 1.3716 0.0635) (xy 0.7493 0.0635)
				(xy 0.7493 -0.8001) (xy -0.7493 -0.8001) (xy -0.7493 0.8001) (xy 0.7493 0.8001) (xy 0.7493 0.0762)
				(xy 1.3716 0.0762) (xy 1.3716 1.6764)
			)
			(stroke
				(width 0)
				(type default)
			)
			(fill no)
			(layer "F.CrtYd")
		)
		(fp_rect
			(start -1.3716 1.6764)
			(end 1.3716 -1.6764)
			(stroke
				(width 0)
				(type default)
			)
			(fill no)
			(layer "F.Fab")
		)
		(pad "1" smd rect
			(at 0.50038 -0.73025)
			(size 0.7112 0.8636)
			(layers "F.Cu" "F.Mask" "F.Paste")
			(net "DRV_ACT_28_34")
		)
		(pad "2" smd rect
			(at -0.50038 -0.73025)
			(size 0.7112 0.8636)
			(layers "F.Cu" "F.Mask" "F.Paste")
			(net "FLT_HDD28_34")
		)
		(pad "3" smd rect
			(at 0.50038 0.73025)
			(size 0.7112 0.8636)
			(layers "F.Cu" "F.Mask" "F.Paste")
			(net "DRV_ACT_28_34_N")
		)
		(pad "4" smd rect
			(at -0.50038 0.73025)
			(size 0.7112 0.8636)
			(layers "F.Cu" "F.Mask" "F.Paste")
			(net "FLT_HDD28_34_N")
		)
	)
	(footprint ""
		(layer "B.Cu")
		(at 138.811 -3.302 -90)
		(property "Reference" "R21"
			(at 0 0 90)
			(layer "B.SilkS")
			(hide yes)
			(effects
				(font
					(size 1.27 1.27)
				)
				(justify mirror)
			)
		)
		(property "Value" "4K7R2F-GP"
			(at -0.064008 -3.993896 270)
			(unlocked yes)
			(layer "B.Fab")
			(hide yes)
			(effects
				(font
					(size 1.016 1.016)
					(thickness 0.1524)
				)
				(justify mirror)
			)
		)
		(property "Device Type" "R402H16"
			(at -0.064008 -5.517896 270)
			(unlocked yes)
			(layer "B.Fab")
			(hide yes)
			(effects
				(font
					(size 1.016 1.016)
					(thickness 0.1524)
				)
				(justify mirror)
			)
		)
		(duplicate_pad_numbers_are_jumpers no)
		(fp_line
			(start -0.508 -0.9398)
			(end 0.508 -0.9398)
			(stroke
				(width 0.1524)
				(type default)
			)
			(layer "B.SilkS")
		)
		(fp_line
			(start 0.508 -0.9398)
			(end 0.508 0.9398)
			(stroke
				(width 0.1524)
				(type default)
			)
			(layer "B.SilkS")
		)
		(fp_rect
			(start 0.508 0.9398)
			(end -0.508 -0.9398)
			(stroke
				(width 0)
				(type default)
			)
			(fill no)
			(layer "B.CrtYd")
		)
		(fp_rect
			(start 0.508 0.9398)
			(end -0.508 -0.9398)
			(stroke
				(width 0)
				(type default)
			)
			(fill no)
			(layer "B.Fab")
		)
		(pad "1" smd custom
			(at 0 -0.4445 90)
			(size 0.1397 0.1397)
			(layers "B.Cu" "B.Mask" "B.Paste")
			(net "DRIVE_A_28_34_FLT_LED")
			(options
				(clearance outline)
				(anchor circle)
			)
			(primitives
				(gr_poly
					(pts
						(arc
							(start -0.1778 0.2794)
							(mid -0.249642 0.249642)
							(end -0.2794 0.1778)
						)
						(arc
							(start -0.2794 -0.1778)
							(mid -0.249642 -0.249642)
							(end -0.1778 -0.2794)
						)
						(arc
							(start 0.1778 -0.2794)
							(mid 0.249642 -0.249642)
							(end 0.2794 -0.1778)
						)
						(arc
							(start 0.2794 0.1778)
							(mid 0.249642 0.249642)
							(end 0.1778 0.2794)
						)
					)
					(width 0)
					(fill yes)
				)
			)
		)
		(pad "2" smd custom
			(at 0 0.4445 90)
			(size 0.1397 0.1397)
			(layers "B.Cu" "B.Mask" "B.Paste")
			(net "GND")
			(options
				(clearance outline)
				(anchor circle)
			)
			(primitives
				(gr_poly
					(pts
						(arc
							(start -0.1778 0.2794)
							(mid -0.249642 0.249642)
							(end -0.2794 0.1778)
						)
						(arc
							(start -0.2794 -0.1778)
							(mid -0.249642 -0.249642)
							(end -0.1778 -0.2794)
						)
						(arc
							(start 0.1778 -0.2794)
							(mid 0.249642 -0.249642)
							(end 0.2794 -0.1778)
						)
						(arc
							(start 0.2794 0.1778)
							(mid 0.249642 0.249642)
							(end 0.1778 0.2794)
						)
					)
					(width 0)
					(fill yes)
				)
			)
		)
	)
	(footprint ""
		(layer "B.Cu")
		(at 162.1282 -3.1242 -90)
		(property "Reference" "R23"
			(at 0 0 90)
			(layer "B.SilkS")
			(hide yes)
			(effects
				(font
					(size 1.27 1.27)
				)
				(justify mirror)
			)
		)
		(property "Value" "4K7R2F-GP"
			(at -0.064008 -3.993896 270)
			(unlocked yes)
			(layer "B.Fab")
			(hide yes)
			(effects
				(font
					(size 1.016 1.016)
					(thickness 0.1524)
				)
				(justify mirror)
			)
		)
		(property "Device Type" "R402H16"
			(at -0.064008 -5.517896 270)
			(unlocked yes)
			(layer "B.Fab")
			(hide yes)
			(effects
				(font
					(size 1.016 1.016)
					(thickness 0.1524)
				)
				(justify mirror)
			)
		)
		(duplicate_pad_numbers_are_jumpers no)
		(fp_line
			(start -0.508 -0.9398)
			(end 0.508 -0.9398)
			(stroke
				(width 0.1524)
				(type default)
			)
			(layer "B.SilkS")
		)
		(fp_line
			(start 0.508 -0.9398)
			(end 0.508 0.9398)
			(stroke
				(width 0.1524)
				(type default)
			)
			(layer "B.SilkS")
		)
		(fp_rect
			(start 0.508 0.9398)
			(end -0.508 -0.9398)
			(stroke
				(width 0)
				(type default)
			)
			(fill no)
			(layer "B.CrtYd")
		)
		(fp_rect
			(start 0.508 0.9398)
			(end -0.508 -0.9398)
			(stroke
				(width 0)
				(type default)
			)
			(fill no)
			(layer "B.Fab")
		)
		(pad "1" smd custom
			(at 0 -0.4445 90)
			(size 0.1397 0.1397)
			(layers "B.Cu" "B.Mask" "B.Paste")
			(net "DRIVE_A_29_35_FLT_LED")
			(options
				(clearance outline)
				(anchor circle)
			)
			(primitives
				(gr_poly
					(pts
						(arc
							(start -0.1778 0.2794)
							(mid -0.249642 0.249642)
							(end -0.2794 0.1778)
						)
						(arc
							(start -0.2794 -0.1778)
							(mid -0.249642 -0.249642)
							(end -0.1778 -0.2794)
						)
						(arc
							(start 0.1778 -0.2794)
							(mid 0.249642 -0.249642)
							(end 0.2794 -0.1778)
						)
						(arc
							(start 0.2794 0.1778)
							(mid 0.249642 0.249642)
							(end 0.1778 0.2794)
						)
					)
					(width 0)
					(fill yes)
				)
			)
		)
		(pad "2" smd custom
			(at 0 0.4445 90)
			(size 0.1397 0.1397)
			(layers "B.Cu" "B.Mask" "B.Paste")
			(net "GND")
			(options
				(clearance outline)
				(anchor circle)
			)
			(primitives
				(gr_poly
					(pts
						(arc
							(start -0.1778 0.2794)
							(mid -0.249642 0.249642)
							(end -0.2794 0.1778)
						)
						(arc
							(start -0.2794 -0.1778)
							(mid -0.249642 -0.249642)
							(end -0.1778 -0.2794)
						)
						(arc
							(start 0.1778 -0.2794)
							(mid 0.249642 -0.249642)
							(end 0.2794 -0.1778)
						)
						(arc
							(start 0.2794 0.1778)
							(mid 0.249642 0.249642)
							(end 0.1778 0.2794)
						)
					)
					(width 0)
					(fill yes)
				)
			)
		)
	)
	(footprint ""
		(layer "B.Cu")
		(at 159.512 -5.7404 180)
		(property "Reference" "R11"
			(at 0 0 0)
			(layer "B.SilkS")
			(hide yes)
			(effects
				(font
					(size 1.27 1.27)
				)
				(justify mirror)
			)
		)
		(property "Value" "130R3F-GP"
			(at 0.0254 -2.5146 180)
			(unlocked yes)
			(layer "B.Fab")
			(hide yes)
			(effects
				(font
					(size 1.016 1.016)
					(thickness 0.1524)
				)
				(justify mirror)
			)
		)
		(property "Device Type" "R603H22"
			(at 0.0254 -4.0386 180)
			(unlocked yes)
			(layer "B.Fab")
			(hide yes)
			(effects
				(font
					(size 1.016 1.016)
					(thickness 0.1524)
				)
				(justify mirror)
			)
		)
		(duplicate_pad_numbers_are_jumpers no)
		(fp_line
			(start 0.4826 0)
			(end 0.2032 0)
			(stroke
				(width 0.2032)
				(type default)
			)
			(layer "B.SilkS")
		)
		(fp_line
			(start -0.2032 0)
			(end -0.4826 0)
			(stroke
				(width 0.2032)
				(type default)
			)
			(layer "B.SilkS")
		)
		(fp_rect
			(start 0.5842 1.3335)
			(end -0.5842 -1.3335)
			(stroke
				(width 0)
				(type default)
			)
			(fill no)
			(layer "B.CrtYd")
		)
		(fp_rect
			(start 0.5842 1.3335)
			(end -0.5842 -1.3335)
			(stroke
				(width 0)
				(type default)
			)
			(fill no)
			(layer "B.Fab")
		)
		(pad "1" smd custom
			(at 0 -0.762)
			(size 0.2159 0.2159)
			(layers "B.Cu" "B.Mask" "B.Paste")
			(net "P5V_A")
			(options
				(clearance outline)
				(anchor circle)
			)
			(primitives
				(gr_poly
					(pts
						(arc
							(start -0.3302 0.4318)
							(mid -0.402042 0.402042)
							(end -0.4318 0.3302)
						)
						(arc
							(start -0.4318 -0.3302)
							(mid -0.402042 -0.402042)
							(end -0.3302 -0.4318)
						)
						(arc
							(start 0.3302 -0.4318)
							(mid 0.402042 -0.402042)
							(end 0.4318 -0.3302)
						)
						(arc
							(start 0.4318 0.3302)
							(mid 0.402042 0.402042)
							(end 0.3302 0.4318)
						)
					)
					(width 0)
					(fill yes)
				)
			)
		)
		(pad "2" smd custom
			(at 0 0.762)
			(size 0.2159 0.2159)
			(layers "B.Cu" "B.Mask" "B.Paste")
			(net "FLT_HDD29_35")
			(options
				(clearance outline)
				(anchor circle)
			)
			(primitives
				(gr_poly
					(pts
						(arc
							(start -0.3302 0.4318)
							(mid -0.402042 0.402042)
							(end -0.4318 0.3302)
						)
						(arc
							(start -0.4318 -0.3302)
							(mid -0.402042 -0.402042)
							(end -0.3302 -0.4318)
						)
						(arc
							(start 0.3302 -0.4318)
							(mid 0.402042 -0.402042)
							(end 0.4318 -0.3302)
						)
						(arc
							(start 0.4318 0.3302)
							(mid 0.402042 0.402042)
							(end 0.3302 0.4318)
						)
					)
					(width 0)
					(fill yes)
				)
			)
		)
	)
	(footprint ""
		(layer "B.Cu")
		(at 64.696594 -3.24358 -90)
		(property "Reference" "R18"
			(at 0 0 90)
			(layer "B.SilkS")
			(hide yes)
			(effects
				(font
					(size 1.27 1.27)
				)
				(justify mirror)
			)
		)
		(property "Value" "4K7R2F-GP"
			(at -0.064008 -3.993896 270)
			(unlocked yes)
			(layer "B.Fab")
			(hide yes)
			(effects
				(font
					(size 1.016 1.016)
					(thickness 0.1524)
				)
				(justify mirror)
			)
		)
		(property "Device Type" "R402H16"
			(at -0.064008 -5.517896 270)
			(unlocked yes)
			(layer "B.Fab")
			(hide yes)
			(effects
				(font
					(size 1.016 1.016)
					(thickness 0.1524)
				)
				(justify mirror)
			)
		)
		(duplicate_pad_numbers_are_jumpers no)
		(fp_line
			(start -0.508 -0.9398)
			(end 0.508 -0.9398)
			(stroke
				(width 0.1524)
				(type default)
			)
			(layer "B.SilkS")
		)
		(fp_line
			(start 0.508 -0.9398)
			(end 0.508 0.9398)
			(stroke
				(width 0.1524)
				(type default)
			)
			(layer "B.SilkS")
		)
		(fp_rect
			(start 0.508 0.9398)
			(end -0.508 -0.9398)
			(stroke
				(width 0)
				(type default)
			)
			(fill no)
			(layer "B.CrtYd")
		)
		(fp_rect
			(start 0.508 0.9398)
			(end -0.508 -0.9398)
			(stroke
				(width 0)
				(type default)
			)
			(fill no)
			(layer "B.Fab")
		)
		(pad "1" smd custom
			(at 0 -0.4445 90)
			(size 0.1397 0.1397)
			(layers "B.Cu" "B.Mask" "B.Paste")
			(net "DRIVE_A_26_32_ACT")
			(options
				(clearance outline)
				(anchor circle)
			)
			(primitives
				(gr_poly
					(pts
						(arc
							(start -0.1778 0.2794)
							(mid -0.249642 0.249642)
							(end -0.2794 0.1778)
						)
						(arc
							(start -0.2794 -0.1778)
							(mid -0.249642 -0.249642)
							(end -0.1778 -0.2794)
						)
						(arc
							(start 0.1778 -0.2794)
							(mid 0.249642 -0.249642)
							(end 0.2794 -0.1778)
						)
						(arc
							(start 0.2794 0.1778)
							(mid 0.249642 0.249642)
							(end 0.1778 0.2794)
						)
					)
					(width 0)
					(fill yes)
				)
			)
		)
		(pad "2" smd custom
			(at 0 0.4445 90)
			(size 0.1397 0.1397)
			(layers "B.Cu" "B.Mask" "B.Paste")
			(net "GND")
			(options
				(clearance outline)
				(anchor circle)
			)
			(primitives
				(gr_poly
					(pts
						(arc
							(start -0.1778 0.2794)
							(mid -0.249642 0.249642)
							(end -0.2794 0.1778)
						)
						(arc
							(start -0.2794 -0.1778)
							(mid -0.249642 -0.249642)
							(end -0.1778 -0.2794)
						)
						(arc
							(start 0.1778 -0.2794)
							(mid 0.249642 -0.249642)
							(end 0.2794 -0.1778)
						)
						(arc
							(start 0.2794 0.1778)
							(mid 0.249642 0.249642)
							(end 0.1778 0.2794)
						)
					)
					(width 0)
					(fill yes)
				)
			)
		)
	)
	(footprint ""
		(layer "B.Cu")
		(at 32.0294 -5.0546)
		(property "Reference" "Q4"
			(at 0 0 0)
			(layer "B.SilkS")
			(hide yes)
			(effects
				(font
					(size 1.27 1.27)
				)
				(justify mirror)
			)
		)
		(property "Value" "SSM3K324R-GP"
			(at -0.127 -8.9662 0)
			(unlocked yes)
			(layer "B.Fab")
			(hide yes)
			(effects
				(font
					(size 1.016 1.016)
					(thickness 0.1524)
				)
				(justify mirror)
			)
		)
		(property "Device Type" "SOT23DGS2D4H35"
			(at -0.127 -10.4902 0)
			(unlocked yes)
			(layer "B.Fab")
			(hide yes)
			(effects
				(font
					(size 1.016 1.016)
					(thickness 0.1524)
				)
				(justify mirror)
			)
		)
		(duplicate_pad_numbers_are_jumpers no)
		(fp_line
			(start -1.651 -1.778)
			(end 1.651 -1.778)
			(stroke
				(width 0.1524)
				(type default)
			)
			(layer "B.SilkS")
		)
		(fp_line
			(start -1.651 1.778)
			(end -1.651 -1.778)
			(stroke
				(width 0.1524)
				(type default)
			)
			(layer "B.SilkS")
		)
		(fp_line
			(start 1.651 -1.778)
			(end 1.651 1.778)
			(stroke
				(width 0.1524)
				(type default)
			)
			(layer "B.SilkS")
		)
		(fp_line
			(start 1.651 1.778)
			(end -1.651 1.778)
			(stroke
				(width 0.1524)
				(type default)
			)
			(layer "B.SilkS")
		)
		(fp_poly
			(pts
				(xy 1.778 1.8796) (xy 1.778 -1.8796) (xy -1.778 -1.8796) (xy -1.778 1.8796)
			)
			(stroke
				(width 0)
				(type default)
			)
			(fill no)
			(layer "B.CrtYd")
		)
		(fp_poly
			(pts
				(xy 1.778 1.8796) (xy 1.778 -1.8796) (xy -1.778 -1.8796) (xy -1.778 1.8796)
			)
			(stroke
				(width 0)
				(type default)
			)
			(fill no)
			(layer "B.Fab")
		)
		(pad "D" smd custom
			(at 0 -0.9525 180)
			(size 0.1905 0.1905)
			(layers "B.Cu" "B.Mask" "B.Paste")
			(net "DRV_ACT_25_31_N")
			(options
				(clearance outline)
				(anchor circle)
			)
			(primitives
				(gr_poly
					(pts
						(arc
							(start -0.1778 -0.5715)
							(mid -0.321484 -0.511984)
							(end -0.381 -0.3683)
						)
						(arc
							(start -0.381 0.3683)
							(mid -0.321484 0.511984)
							(end -0.1778 0.5715)
						)
						(arc
							(start 0.1778 0.5715)
							(mid 0.321484 0.511984)
							(end 0.381 0.3683)
						)
						(arc
							(start 0.381 -0.3683)
							(mid 0.321484 -0.511984)
							(end 0.1778 -0.5715)
						)
					)
					(width 0)
					(fill yes)
				)
			)
		)
		(pad "G" smd custom
			(at 0.98425 0.9525 180)
			(size 0.1905 0.1905)
			(layers "B.Cu" "B.Mask" "B.Paste")
			(net "DRIVE_A_25_31_ACT")
			(options
				(clearance outline)
				(anchor circle)
			)
			(primitives
				(gr_poly
					(pts
						(arc
							(start -0.1778 -0.5715)
							(mid -0.321484 -0.511984)
							(end -0.381 -0.3683)
						)
						(arc
							(start -0.381 0.3683)
							(mid -0.321484 0.511984)
							(end -0.1778 0.5715)
						)
						(arc
							(start 0.1778 0.5715)
							(mid 0.321484 0.511984)
							(end 0.381 0.3683)
						)
						(arc
							(start 0.381 -0.3683)
							(mid 0.321484 -0.511984)
							(end 0.1778 -0.5715)
						)
					)
					(width 0)
					(fill yes)
				)
			)
		)
		(pad "S" smd custom
			(at -0.98425 0.9525 180)
			(size 0.1905 0.1905)
			(layers "B.Cu" "B.Mask" "B.Paste")
			(net "GND")
			(options
				(clearance outline)
				(anchor circle)
			)
			(primitives
				(gr_poly
					(pts
						(arc
							(start -0.1778 -0.5715)
							(mid -0.321484 -0.511984)
							(end -0.381 -0.3683)
						)
						(arc
							(start -0.381 0.3683)
							(mid -0.321484 0.511984)
							(end -0.1778 0.5715)
						)
						(arc
							(start 0.1778 0.5715)
							(mid 0.321484 0.511984)
							(end 0.381 0.3683)
						)
						(arc
							(start 0.381 -0.3683)
							(mid 0.321484 -0.511984)
							(end 0.1778 -0.5715)
						)
					)
					(width 0)
					(fill yes)
				)
			)
		)
	)
	(footprint ""
		(layer "B.Cu")
		(at 22.3012 -5.4102)
		(property "Reference" "Q2"
			(at 0 0 0)
			(layer "B.SilkS")
			(hide yes)
			(effects
				(font
					(size 1.27 1.27)
				)
				(justify mirror)
			)
		)
		(property "Value" "SSM3K324R-GP"
			(at -0.127 -8.9662 0)
			(unlocked yes)
			(layer "B.Fab")
			(hide yes)
			(effects
				(font
					(size 1.016 1.016)
					(thickness 0.1524)
				)
				(justify mirror)
			)
		)
		(property "Device Type" "SOT23DGS2D4H35"
			(at -0.127 -10.4902 0)
			(unlocked yes)
			(layer "B.Fab")
			(hide yes)
			(effects
				(font
					(size 1.016 1.016)
					(thickness 0.1524)
				)
				(justify mirror)
			)
		)
		(duplicate_pad_numbers_are_jumpers no)
		(fp_line
			(start -1.651 -1.778)
			(end 1.651 -1.778)
			(stroke
				(width 0.1524)
				(type default)
			)
			(layer "B.SilkS")
		)
		(fp_line
			(start -1.651 1.778)
			(end -1.651 -1.778)
			(stroke
				(width 0.1524)
				(type default)
			)
			(layer "B.SilkS")
		)
		(fp_line
			(start 1.651 -1.778)
			(end 1.651 1.778)
			(stroke
				(width 0.1524)
				(type default)
			)
			(layer "B.SilkS")
		)
		(fp_line
			(start 1.651 1.778)
			(end -1.651 1.778)
			(stroke
				(width 0.1524)
				(type default)
			)
			(layer "B.SilkS")
		)
		(fp_poly
			(pts
				(xy 1.778 1.8796) (xy 1.778 -1.8796) (xy -1.778 -1.8796) (xy -1.778 1.8796)
			)
			(stroke
				(width 0)
				(type default)
			)
			(fill no)
			(layer "B.CrtYd")
		)
		(fp_poly
			(pts
				(xy 1.778 1.8796) (xy 1.778 -1.8796) (xy -1.778 -1.8796) (xy -1.778 1.8796)
			)
			(stroke
				(width 0)
				(type default)
			)
			(fill no)
			(layer "B.Fab")
		)
		(pad "D" smd custom
			(at 0 -0.9525 180)
			(size 0.1905 0.1905)
			(layers "B.Cu" "B.Mask" "B.Paste")
			(net "DRV_ACT_24_30_N")
			(options
				(clearance outline)
				(anchor circle)
			)
			(primitives
				(gr_poly
					(pts
						(arc
							(start -0.1778 -0.5715)
							(mid -0.321484 -0.511984)
							(end -0.381 -0.3683)
						)
						(arc
							(start -0.381 0.3683)
							(mid -0.321484 0.511984)
							(end -0.1778 0.5715)
						)
						(arc
							(start 0.1778 0.5715)
							(mid 0.321484 0.511984)
							(end 0.381 0.3683)
						)
						(arc
							(start 0.381 -0.3683)
							(mid 0.321484 -0.511984)
							(end 0.1778 -0.5715)
						)
					)
					(width 0)
					(fill yes)
				)
			)
		)
		(pad "G" smd custom
			(at 0.98425 0.9525 180)
			(size 0.1905 0.1905)
			(layers "B.Cu" "B.Mask" "B.Paste")
			(net "DRIVE_A_24_30_ACT")
			(options
				(clearance outline)
				(anchor circle)
			)
			(primitives
				(gr_poly
					(pts
						(arc
							(start -0.1778 -0.5715)
							(mid -0.321484 -0.511984)
							(end -0.381 -0.3683)
						)
						(arc
							(start -0.381 0.3683)
							(mid -0.321484 0.511984)
							(end -0.1778 0.5715)
						)
						(arc
							(start 0.1778 0.5715)
							(mid 0.321484 0.511984)
							(end 0.381 0.3683)
						)
						(arc
							(start 0.381 -0.3683)
							(mid 0.321484 -0.511984)
							(end 0.1778 -0.5715)
						)
					)
					(width 0)
					(fill yes)
				)
			)
		)
		(pad "S" smd custom
			(at -0.98425 0.9525 180)
			(size 0.1905 0.1905)
			(layers "B.Cu" "B.Mask" "B.Paste")
			(net "GND")
			(options
				(clearance outline)
				(anchor circle)
			)
			(primitives
				(gr_poly
					(pts
						(arc
							(start -0.1778 -0.5715)
							(mid -0.321484 -0.511984)
							(end -0.381 -0.3683)
						)
						(arc
							(start -0.381 0.3683)
							(mid -0.321484 0.511984)
							(end -0.1778 0.5715)
						)
						(arc
							(start 0.1778 0.5715)
							(mid 0.321484 0.511984)
							(end 0.381 0.3683)
						)
						(arc
							(start 0.381 -0.3683)
							(mid 0.321484 -0.511984)
							(end 0.1778 -0.5715)
						)
					)
					(width 0)
					(fill yes)
				)
			)
		)
	)
	(footprint ""
		(layer "B.Cu")
		(at 112.395 -6.0198 180)
		(property "Reference" "R8"
			(at 0 0 0)
			(layer "B.SilkS")
			(hide yes)
			(effects
				(font
					(size 1.27 1.27)
				)
				(justify mirror)
			)
		)
		(property "Value" "91R3F-1-GP"
			(at 0.0254 -2.5146 180)
			(unlocked yes)
			(layer "B.Fab")
			(hide yes)
			(effects
				(font
					(size 1.016 1.016)
					(thickness 0.1524)
				)
				(justify mirror)
			)
		)
		(property "Device Type" "R603H22"
			(at 0.0254 -4.0386 180)
			(unlocked yes)
			(layer "B.Fab")
			(hide yes)
			(effects
				(font
					(size 1.016 1.016)
					(thickness 0.1524)
				)
				(justify mirror)
			)
		)
		(duplicate_pad_numbers_are_jumpers no)
		(fp_line
			(start 0.4826 0)
			(end 0.2032 0)
			(stroke
				(width 0.2032)
				(type default)
			)
			(layer "B.SilkS")
		)
		(fp_line
			(start -0.2032 0)
			(end -0.4826 0)
			(stroke
				(width 0.2032)
				(type default)
			)
			(layer "B.SilkS")
		)
		(fp_rect
			(start 0.5842 1.3335)
			(end -0.5842 -1.3335)
			(stroke
				(width 0)
				(type default)
			)
			(fill no)
			(layer "B.CrtYd")
		)
		(fp_rect
			(start 0.5842 1.3335)
			(end -0.5842 -1.3335)
			(stroke
				(width 0)
				(type default)
			)
			(fill no)
			(layer "B.Fab")
		)
		(pad "1" smd custom
			(at 0 -0.762)
			(size 0.2159 0.2159)
			(layers "B.Cu" "B.Mask" "B.Paste")
			(net "P5V_A")
			(options
				(clearance outline)
				(anchor circle)
			)
			(primitives
				(gr_poly
					(pts
						(arc
							(start -0.3302 0.4318)
							(mid -0.402042 0.402042)
							(end -0.4318 0.3302)
						)
						(arc
							(start -0.4318 -0.3302)
							(mid -0.402042 -0.402042)
							(end -0.3302 -0.4318)
						)
						(arc
							(start 0.3302 -0.4318)
							(mid 0.402042 -0.402042)
							(end 0.4318 -0.3302)
						)
						(arc
							(start 0.4318 0.3302)
							(mid 0.402042 0.402042)
							(end 0.3302 0.4318)
						)
					)
					(width 0)
					(fill yes)
				)
			)
		)
		(pad "2" smd custom
			(at 0 0.762)
			(size 0.2159 0.2159)
			(layers "B.Cu" "B.Mask" "B.Paste")
			(net "DRV_ACT_27_33")
			(options
				(clearance outline)
				(anchor circle)
			)
			(primitives
				(gr_poly
					(pts
						(arc
							(start -0.3302 0.4318)
							(mid -0.402042 0.402042)
							(end -0.4318 0.3302)
						)
						(arc
							(start -0.4318 -0.3302)
							(mid -0.402042 -0.402042)
							(end -0.3302 -0.4318)
						)
						(arc
							(start 0.3302 -0.4318)
							(mid 0.402042 -0.402042)
							(end 0.4318 -0.3302)
						)
						(arc
							(start 0.4318 0.3302)
							(mid 0.402042 0.402042)
							(end 0.3302 0.4318)
						)
					)
					(width 0)
					(fill yes)
				)
			)
		)
	)
	(footprint ""
		(layer "B.Cu")
		(at 167.9194 -5.7658 180)
		(property "Reference" "R12"
			(at 0 0 0)
			(layer "B.SilkS")
			(hide yes)
			(effects
				(font
					(size 1.27 1.27)
				)
				(justify mirror)
			)
		)
		(property "Value" "91R3F-1-GP"
			(at 0.0254 -2.5146 180)
			(unlocked yes)
			(layer "B.Fab")
			(hide yes)
			(effects
				(font
					(size 1.016 1.016)
					(thickness 0.1524)
				)
				(justify mirror)
			)
		)
		(property "Device Type" "R603H22"
			(at 0.0254 -4.0386 180)
			(unlocked yes)
			(layer "B.Fab")
			(hide yes)
			(effects
				(font
					(size 1.016 1.016)
					(thickness 0.1524)
				)
				(justify mirror)
			)
		)
		(duplicate_pad_numbers_are_jumpers no)
		(fp_line
			(start 0.4826 0)
			(end 0.2032 0)
			(stroke
				(width 0.2032)
				(type default)
			)
			(layer "B.SilkS")
		)
		(fp_line
			(start -0.2032 0)
			(end -0.4826 0)
			(stroke
				(width 0.2032)
				(type default)
			)
			(layer "B.SilkS")
		)
		(fp_rect
			(start 0.5842 1.3335)
			(end -0.5842 -1.3335)
			(stroke
				(width 0)
				(type default)
			)
			(fill no)
			(layer "B.CrtYd")
		)
		(fp_rect
			(start 0.5842 1.3335)
			(end -0.5842 -1.3335)
			(stroke
				(width 0)
				(type default)
			)
			(fill no)
			(layer "B.Fab")
		)
		(pad "1" smd custom
			(at 0 -0.762)
			(size 0.2159 0.2159)
			(layers "B.Cu" "B.Mask" "B.Paste")
			(net "P5V_A")
			(options
				(clearance outline)
				(anchor circle)
			)
			(primitives
				(gr_poly
					(pts
						(arc
							(start -0.3302 0.4318)
							(mid -0.402042 0.402042)
							(end -0.4318 0.3302)
						)
						(arc
							(start -0.4318 -0.3302)
							(mid -0.402042 -0.402042)
							(end -0.3302 -0.4318)
						)
						(arc
							(start 0.3302 -0.4318)
							(mid 0.402042 -0.402042)
							(end 0.4318 -0.3302)
						)
						(arc
							(start 0.4318 0.3302)
							(mid 0.402042 0.402042)
							(end 0.3302 0.4318)
						)
					)
					(width 0)
					(fill yes)
				)
			)
		)
		(pad "2" smd custom
			(at 0 0.762)
			(size 0.2159 0.2159)
			(layers "B.Cu" "B.Mask" "B.Paste")
			(net "DRV_ACT_29_35")
			(options
				(clearance outline)
				(anchor circle)
			)
			(primitives
				(gr_poly
					(pts
						(arc
							(start -0.3302 0.4318)
							(mid -0.402042 0.402042)
							(end -0.4318 0.3302)
						)
						(arc
							(start -0.4318 -0.3302)
							(mid -0.402042 -0.402042)
							(end -0.3302 -0.4318)
						)
						(arc
							(start 0.3302 -0.4318)
							(mid 0.402042 -0.402042)
							(end 0.4318 -0.3302)
						)
						(arc
							(start 0.4318 0.3302)
							(mid 0.402042 0.402042)
							(end 0.3302 0.4318)
						)
					)
					(width 0)
					(fill yes)
				)
			)
		)
	)
	(footprint ""
		(layer "B.Cu")
		(at 32.893 -2.6416 -90)
		(property "Reference" "R16"
			(at 0 0 90)
			(layer "B.SilkS")
			(hide yes)
			(effects
				(font
					(size 1.27 1.27)
				)
				(justify mirror)
			)
		)
		(property "Value" "4K7R2F-GP"
			(at -0.064008 -3.993896 270)
			(unlocked yes)
			(layer "B.Fab")
			(hide yes)
			(effects
				(font
					(size 1.016 1.016)
					(thickness 0.1524)
				)
				(justify mirror)
			)
		)
		(property "Device Type" "R402H16"
			(at -0.064008 -5.517896 270)
			(unlocked yes)
			(layer "B.Fab")
			(hide yes)
			(effects
				(font
					(size 1.016 1.016)
					(thickness 0.1524)
				)
				(justify mirror)
			)
		)
		(duplicate_pad_numbers_are_jumpers no)
		(fp_line
			(start -0.508 -0.9398)
			(end 0.508 -0.9398)
			(stroke
				(width 0.1524)
				(type default)
			)
			(layer "B.SilkS")
		)
		(fp_line
			(start 0.508 -0.9398)
			(end 0.508 0.9398)
			(stroke
				(width 0.1524)
				(type default)
			)
			(layer "B.SilkS")
		)
		(fp_rect
			(start 0.508 0.9398)
			(end -0.508 -0.9398)
			(stroke
				(width 0)
				(type default)
			)
			(fill no)
			(layer "B.CrtYd")
		)
		(fp_rect
			(start 0.508 0.9398)
			(end -0.508 -0.9398)
			(stroke
				(width 0)
				(type default)
			)
			(fill no)
			(layer "B.Fab")
		)
		(pad "1" smd custom
			(at 0 -0.4445 90)
			(size 0.1397 0.1397)
			(layers "B.Cu" "B.Mask" "B.Paste")
			(net "DRIVE_A_25_31_ACT")
			(options
				(clearance outline)
				(anchor circle)
			)
			(primitives
				(gr_poly
					(pts
						(arc
							(start -0.1778 0.2794)
							(mid -0.249642 0.249642)
							(end -0.2794 0.1778)
						)
						(arc
							(start -0.2794 -0.1778)
							(mid -0.249642 -0.249642)
							(end -0.1778 -0.2794)
						)
						(arc
							(start 0.1778 -0.2794)
							(mid 0.249642 -0.249642)
							(end 0.2794 -0.1778)
						)
						(arc
							(start 0.2794 0.1778)
							(mid 0.249642 0.249642)
							(end 0.1778 0.2794)
						)
					)
					(width 0)
					(fill yes)
				)
			)
		)
		(pad "2" smd custom
			(at 0 0.4445 90)
			(size 0.1397 0.1397)
			(layers "B.Cu" "B.Mask" "B.Paste")
			(net "GND")
			(options
				(clearance outline)
				(anchor circle)
			)
			(primitives
				(gr_poly
					(pts
						(arc
							(start -0.1778 0.2794)
							(mid -0.249642 0.249642)
							(end -0.2794 0.1778)
						)
						(arc
							(start -0.2794 -0.1778)
							(mid -0.249642 -0.249642)
							(end -0.1778 -0.2794)
						)
						(arc
							(start 0.1778 -0.2794)
							(mid 0.249642 -0.249642)
							(end 0.2794 -0.1778)
						)
						(arc
							(start 0.2794 0.1778)
							(mid 0.249642 0.249642)
							(end 0.1778 0.2794)
						)
					)
					(width 0)
					(fill yes)
				)
			)
		)
	)
	(footprint ""
		(layer "B.Cu")
		(at 138.4554 -5.715)
		(property "Reference" "Q9"
			(at 0 0 0)
			(layer "B.SilkS")
			(hide yes)
			(effects
				(font
					(size 1.27 1.27)
				)
				(justify mirror)
			)
		)
		(property "Value" "2N7002K-2-GP"
			(at -0.127 -8.9662 0)
			(unlocked yes)
			(layer "B.Fab")
			(hide yes)
			(effects
				(font
					(size 1.016 1.016)
					(thickness 0.1524)
				)
				(justify mirror)
			)
		)
		(property "Device Type" "SOT23DGS2D4H44"
			(at -0.127 -10.4902 0)
			(unlocked yes)
			(layer "B.Fab")
			(hide yes)
			(effects
				(font
					(size 1.016 1.016)
					(thickness 0.1524)
				)
				(justify mirror)
			)
		)
		(duplicate_pad_numbers_are_jumpers no)
		(fp_line
			(start -1.651 -1.778)
			(end 1.651 -1.778)
			(stroke
				(width 0.1524)
				(type default)
			)
			(layer "B.SilkS")
		)
		(fp_line
			(start -1.651 1.778)
			(end -1.651 -1.778)
			(stroke
				(width 0.1524)
				(type default)
			)
			(layer "B.SilkS")
		)
		(fp_line
			(start 1.651 -1.778)
			(end 1.651 1.778)
			(stroke
				(width 0.1524)
				(type default)
			)
			(layer "B.SilkS")
		)
		(fp_line
			(start 1.651 1.778)
			(end -1.651 1.778)
			(stroke
				(width 0.1524)
				(type default)
			)
			(layer "B.SilkS")
		)
		(fp_poly
			(pts
				(xy 1.778 1.8796) (xy 1.778 -1.8796) (xy -1.778 -1.8796) (xy -1.778 1.8796)
			)
			(stroke
				(width 0)
				(type default)
			)
			(fill no)
			(layer "B.CrtYd")
		)
		(fp_poly
			(pts
				(xy 1.778 1.8796) (xy 1.778 -1.8796) (xy -1.778 -1.8796) (xy -1.778 1.8796)
			)
			(stroke
				(width 0)
				(type default)
			)
			(fill no)
			(layer "B.Fab")
		)
		(pad "D" smd custom
			(at 0 -0.9525 180)
			(size 0.1905 0.1905)
			(layers "B.Cu" "B.Mask" "B.Paste")
			(net "FLT_HDD28_34_N")
			(options
				(clearance outline)
				(anchor circle)
			)
			(primitives
				(gr_poly
					(pts
						(arc
							(start -0.1778 -0.5715)
							(mid -0.321484 -0.511984)
							(end -0.381 -0.3683)
						)
						(arc
							(start -0.381 0.3683)
							(mid -0.321484 0.511984)
							(end -0.1778 0.5715)
						)
						(arc
							(start 0.1778 0.5715)
							(mid 0.321484 0.511984)
							(end 0.381 0.3683)
						)
						(arc
							(start 0.381 -0.3683)
							(mid 0.321484 -0.511984)
							(end 0.1778 -0.5715)
						)
					)
					(width 0)
					(fill yes)
				)
			)
		)
		(pad "G" smd custom
			(at 0.98425 0.9525 180)
			(size 0.1905 0.1905)
			(layers "B.Cu" "B.Mask" "B.Paste")
			(net "DRIVE_A_28_34_FLT_LED")
			(options
				(clearance outline)
				(anchor circle)
			)
			(primitives
				(gr_poly
					(pts
						(arc
							(start -0.1778 -0.5715)
							(mid -0.321484 -0.511984)
							(end -0.381 -0.3683)
						)
						(arc
							(start -0.381 0.3683)
							(mid -0.321484 0.511984)
							(end -0.1778 0.5715)
						)
						(arc
							(start 0.1778 0.5715)
							(mid 0.321484 0.511984)
							(end 0.381 0.3683)
						)
						(arc
							(start 0.381 -0.3683)
							(mid 0.321484 -0.511984)
							(end 0.1778 -0.5715)
						)
					)
					(width 0)
					(fill yes)
				)
			)
		)
		(pad "S" smd custom
			(at -0.98425 0.9525 180)
			(size 0.1905 0.1905)
			(layers "B.Cu" "B.Mask" "B.Paste")
			(net "GND")
			(options
				(clearance outline)
				(anchor circle)
			)
			(primitives
				(gr_poly
					(pts
						(arc
							(start -0.1778 -0.5715)
							(mid -0.321484 -0.511984)
							(end -0.381 -0.3683)
						)
						(arc
							(start -0.381 0.3683)
							(mid -0.321484 0.511984)
							(end -0.1778 0.5715)
						)
						(arc
							(start 0.1778 0.5715)
							(mid 0.321484 0.511984)
							(end 0.381 0.3683)
						)
						(arc
							(start 0.381 -0.3683)
							(mid 0.321484 -0.511984)
							(end 0.1778 -0.5715)
						)
					)
					(width 0)
					(fill yes)
				)
			)
		)
	)
	(footprint ""
		(layer "B.Cu")
		(at 38.481 -4.953 -90)
		(property "Reference" "C2"
			(at 0 0 90)
			(layer "B.SilkS")
			(hide yes)
			(effects
				(font
					(size 1.27 1.27)
				)
				(justify mirror)
			)
		)
		(property "Value" "SC10U16V6KX-2GP"
			(at 0.0762 -5.1308 270)
			(unlocked yes)
			(layer "B.Fab")
			(hide yes)
			(effects
				(font
					(size 1.016 1.016)
					(thickness 0.1524)
				)
				(justify mirror)
			)
		)
		(property "Device Type" "C1206H71"
			(at 0.127 -6.6548 270)
			(unlocked yes)
			(layer "B.Fab")
			(hide yes)
			(effects
				(font
					(size 1.016 1.016)
					(thickness 0.1524)
				)
				(justify mirror)
			)
		)
		(duplicate_pad_numbers_are_jumpers no)
		(fp_line
			(start -1.016 2.2352)
			(end 1.016 2.2352)
			(stroke
				(width 0.1524)
				(type default)
			)
			(layer "B.SilkS")
		)
		(fp_line
			(start 1.016 2.2352)
			(end 1.016 0.8382)
			(stroke
				(width 0.1524)
				(type default)
			)
			(layer "B.SilkS")
		)
		(fp_line
			(start -1.016 0.8382)
			(end -1.016 2.2352)
			(stroke
				(width 0.1524)
				(type default)
			)
			(layer "B.SilkS")
		)
		(fp_line
			(start 1.016 -0.8382)
			(end 1.016 -2.2352)
			(stroke
				(width 0.1524)
				(type default)
			)
			(layer "B.SilkS")
		)
		(fp_line
			(start -1.016 -2.2352)
			(end -1.016 -0.8382)
			(stroke
				(width 0.1524)
				(type default)
			)
			(layer "B.SilkS")
		)
		(fp_line
			(start 1.016 -2.2352)
			(end -1.016 -2.2352)
			(stroke
				(width 0.1524)
				(type default)
			)
			(layer "B.SilkS")
		)
		(fp_rect
			(start 1.0922 2.3114)
			(end -1.0922 -2.3114)
			(stroke
				(width 0)
				(type default)
			)
			(fill no)
			(layer "B.CrtYd")
		)
		(fp_poly
			(pts
				(xy -1.0922 -2.3114) (xy -1.0922 2.3114) (xy 1.0922 2.3114) (xy 1.0922 -2.3114)
			)
			(stroke
				(width 0)
				(type default)
			)
			(fill no)
			(layer "B.Fab")
		)
		(pad "1" smd rect
			(at 0 -1.397 90)
			(size 1.651 1.27)
			(layers "B.Cu" "B.Mask" "B.Paste")
			(net "P5V_A")
		)
		(pad "2" smd rect
			(at 0 1.397 90)
			(size 1.651 1.27)
			(layers "B.Cu" "B.Mask" "B.Paste")
			(net "GND")
		)
	)
	(footprint ""
		(layer "B.Cu")
		(at 49.150016 -11.8999)
		(property "Reference" "CN1"
			(at 0 0 0)
			(layer "B.SilkS")
			(hide yes)
			(effects
				(font
					(size 1.27 1.27)
				)
				(justify mirror)
			)
		)
		(property "Value" "AMP-CONN20D-4-GP"
			(at 8.79348 -0.84963 0)
			(unlocked yes)
			(layer "B.Fab")
			(hide yes)
			(effects
				(font
					(size 1.016 1.016)
					(thickness 0.1524)
				)
				(justify mirror)
			)
		)
		(property "Device Type" "G846A20120T1HR"
			(at 8.79348 -2.37363 0)
			(unlocked yes)
			(layer "B.Fab")
			(hide yes)
			(effects
				(font
					(size 1.016 1.016)
					(thickness 0.1524)
				)
				(justify mirror)
			)
		)
		(duplicate_pad_numbers_are_jumpers no)
		(fp_line
			(start -7.5057 0.254)
			(end -7.5057 2.8194)
			(stroke
				(width 0.1524)
				(type default)
			)
			(layer "B.SilkS")
		)
		(fp_line
			(start -7.5057 2.8194)
			(end -5.0546 2.8194)
			(stroke
				(width 0.1524)
				(type default)
			)
			(layer "B.SilkS")
		)
		(fp_line
			(start -6.5532 -2.5527)
			(end -6.5532 0.254)
			(stroke
				(width 0.1524)
				(type default)
			)
			(layer "B.SilkS")
		)
		(fp_line
			(start -6.5532 0.254)
			(end -7.5057 0.254)
			(stroke
				(width 0.1524)
				(type default)
			)
			(layer "B.SilkS")
		)
		(fp_line
			(start -5.0546 -4.064)
			(end -5.0546 -2.5527)
			(stroke
				(width 0.1524)
				(type default)
			)
			(layer "B.SilkS")
		)
		(fp_line
			(start -5.0546 -2.5527)
			(end -6.5532 -2.5527)
			(stroke
				(width 0.1524)
				(type default)
			)
			(layer "B.SilkS")
		)
		(fp_line
			(start -5.0546 2.8194)
			(end -5.0546 4.064)
			(stroke
				(width 0.1524)
				(type default)
			)
			(layer "B.SilkS")
		)
		(fp_line
			(start -5.0546 4.064)
			(end 5.0546 4.064)
			(stroke
				(width 0.1524)
				(type default)
			)
			(layer "B.SilkS")
		)
		(fp_line
			(start 4.0386 -4.1529)
			(end 5.1435 -4.1529)
			(stroke
				(width 0.3302)
				(type default)
			)
			(layer "B.SilkS")
		)
		(fp_line
			(start 5.0546 -4.064)
			(end -5.0546 -4.064)
			(stroke
				(width 0.1524)
				(type default)
			)
			(layer "B.SilkS")
		)
		(fp_line
			(start 5.0546 -2.5527)
			(end 5.0546 -4.064)
			(stroke
				(width 0.1524)
				(type default)
			)
			(layer "B.SilkS")
		)
		(fp_line
			(start 5.0546 2.8194)
			(end 7.5057 2.8194)
			(stroke
				(width 0.1524)
				(type default)
			)
			(layer "B.SilkS")
		)
		(fp_line
			(start 5.0546 4.064)
			(end 5.0546 2.8194)
			(stroke
				(width 0.1524)
				(type default)
			)
			(layer "B.SilkS")
		)
		(fp_line
			(start 5.1435 -4.1529)
			(end 5.1435 -3.1877)
			(stroke
				(width 0.3302)
				(type default)
			)
			(layer "B.SilkS")
		)
		(fp_line
			(start 6.5532 -2.5527)
			(end 5.0546 -2.5527)
			(stroke
				(width 0.1524)
				(type default)
			)
			(layer "B.SilkS")
		)
		(fp_line
			(start 6.5532 0.254)
			(end 6.5532 -2.5527)
			(stroke
				(width 0.1524)
				(type default)
			)
			(layer "B.SilkS")
		)
		(fp_line
			(start 7.5057 0.254)
			(end 6.5532 0.254)
			(stroke
				(width 0.1524)
				(type default)
			)
			(layer "B.SilkS")
		)
		(fp_line
			(start 7.5057 2.8194)
			(end 7.5057 0.254)
			(stroke
				(width 0.1524)
				(type default)
			)
			(layer "B.SilkS")
		)
		(fp_rect
			(start 4.804918 2.097532)
			(end -4.804918 -2.097532)
			(stroke
				(width 0)
				(type default)
			)
			(fill yes)
			(layer "B.SilkS")
		)
		(fp_poly
			(pts
				(xy 4.500118 -4.1402) (xy 3.865118 -4.7752) (xy 5.135118 -4.7752)
			)
			(stroke
				(width 0)
				(type default)
			)
			(fill yes)
			(layer "B.SilkS")
		)
		(fp_poly
			(pts
				(xy 4.8006 3.302) (xy 4.8006 2.2987) (xy 6.9469 2.2987) (xy 6.9469 0.508) (xy 6.2992 0.508) (xy 6.2992 -2.2987)
				(xy 4.8006 -2.2987) (xy 4.8006 -3.302) (xy -4.8006 -3.302) (xy -4.8006 -2.2987) (xy -6.2992 -2.2987)
				(xy -6.2992 0.508) (xy -6.9469 0.508) (xy -6.9469 2.2987) (xy -4.8006 2.2987) (xy -4.8006 3.302)
			)
			(stroke
				(width 0)
				(type default)
			)
			(fill no)
			(layer "B.CrtYd")
		)
		(fp_poly
			(pts
				(xy 5.3086 4.318) (xy 5.3086 3.0734) (xy 7.7597 3.0734) (xy 7.7597 0) (xy 6.8072 0) (xy 6.8072 -2.8067)
				(xy 5.3086 -2.8067) (xy 5.3086 -4.318) (xy -5.3086 -4.318) (xy -5.3086 -2.8067) (xy -6.8072 -2.8067)
				(xy -6.8072 -0.00635) (xy -6.2992 -0.00635) (xy -6.2992 -2.2987) (xy -4.8006 -2.2987) (xy -4.8006 -3.302)
				(xy 4.8006 -3.302) (xy 4.8006 -2.2987) (xy 6.2992 -2.2987) (xy 6.2992 0.508) (xy 6.9469 0.508) (xy 6.9469 2.2987)
				(xy 4.8006 2.2987) (xy 4.8006 3.302) (xy -4.8006 3.302) (xy -4.8006 2.2987) (xy -6.9469 2.2987)
				(xy -6.9469 0.508) (xy -6.2992 0.508) (xy -6.2992 0.00635) (xy -7.7597 0.00635) (xy -7.7597 3.0734)
				(xy -5.3086 3.0734) (xy -5.3086 4.318)
			)
			(stroke
				(width 0)
				(type default)
			)
			(fill no)
			(layer "B.CrtYd")
		)
		(fp_poly
			(pts
				(xy 5.3086 4.318) (xy 5.3086 3.0734) (xy 7.7597 3.0734) (xy 7.7597 0) (xy 6.8072 0) (xy 6.8072 -2.8067)
				(xy 5.3086 -2.8067) (xy 5.3086 -4.318) (xy -5.3086 -4.318) (xy -5.3086 -2.8067) (xy -6.8072 -2.8067)
				(xy -6.8072 0) (xy -7.7597 0) (xy -7.7597 3.0734) (xy -5.3086 3.0734) (xy -5.3086 4.318)
			)
			(stroke
				(width 0)
				(type default)
			)
			(fill no)
			(layer "B.Fab")
		)
		(pad "1" smd rect
			(at 4.500118 -3.050032 180)
			(size 0.6096 1.4986)
			(layers "B.Cu" "B.Mask" "B.Paste")
			(net "DRIVE_A_26_32_FLT_LED")
		)
		(pad "2" smd rect
			(at 4.500118 3.050032 180)
			(size 0.6096 1.4986)
			(layers "B.Cu" "B.Mask" "B.Paste")
			(net "DRIVE_A_27_33_FLT_LED")
		)
		(pad "3" smd rect
			(at 3.50012 -3.050032 180)
			(size 0.6096 1.4986)
			(layers "B.Cu" "B.Mask" "B.Paste")
			(net "DRIVE_A_26_32_ACT")
		)
		(pad "4" smd rect
			(at 3.50012 3.050032 180)
			(size 0.6096 1.4986)
			(layers "B.Cu" "B.Mask" "B.Paste")
			(net "DRIVE_A_27_33_ACT")
		)
		(pad "5" smd rect
			(at 2.500122 -3.050032 180)
			(size 0.6096 1.4986)
			(layers "B.Cu" "B.Mask" "B.Paste")
			(net "Net_23")
		)
		(pad "6" smd rect
			(at 2.500122 3.050032 180)
			(size 0.6096 1.4986)
			(layers "B.Cu" "B.Mask" "B.Paste")
			(net "DRIVE_A_28_34_FLT_LED")
		)
		(pad "7" smd rect
			(at 1.500124 -3.050032 180)
			(size 0.6096 1.4986)
			(layers "B.Cu" "B.Mask" "B.Paste")
			(net "P5V_A")
		)
		(pad "8" smd rect
			(at 1.500124 3.050032 180)
			(size 0.6096 1.4986)
			(layers "B.Cu" "B.Mask" "B.Paste")
			(net "DRIVE_A_28_34_ACT")
		)
		(pad "9" smd rect
			(at 0.500126 -3.050032 180)
			(size 0.6096 1.4986)
			(layers "B.Cu" "B.Mask" "B.Paste")
			(net "P5V_A")
		)
		(pad "10" smd rect
			(at 0.500126 3.050032 180)
			(size 0.6096 1.4986)
			(layers "B.Cu" "B.Mask" "B.Paste")
			(net "DRIVE_A_29_35_FLT_LED")
		)
		(pad "11" smd rect
			(at -0.500126 -3.050032 180)
			(size 0.6096 1.4986)
			(layers "B.Cu" "B.Mask" "B.Paste")
			(net "P5V_A")
		)
		(pad "12" smd rect
			(at -0.500126 3.050032 180)
			(size 0.6096 1.4986)
			(layers "B.Cu" "B.Mask" "B.Paste")
			(net "DRIVE_A_29_35_ACT")
		)
		(pad "13" smd rect
			(at -1.500124 -3.050032 180)
			(size 0.6096 1.4986)
			(layers "B.Cu" "B.Mask" "B.Paste")
			(net "Net_62")
		)
		(pad "14" smd rect
			(at -1.500124 3.050032 180)
			(size 0.6096 1.4986)
			(layers "B.Cu" "B.Mask" "B.Paste")
			(net "DRIVE_A_24_30_FLT_LED")
		)
		(pad "15" smd rect
			(at -2.500122 -3.050032 180)
			(size 0.6096 1.4986)
			(layers "B.Cu" "B.Mask" "B.Paste")
			(net "GND")
		)
		(pad "16" smd rect
			(at -2.500122 3.050032 180)
			(size 0.6096 1.4986)
			(layers "B.Cu" "B.Mask" "B.Paste")
			(net "DRIVE_A_24_30_ACT")
		)
		(pad "17" smd rect
			(at -3.50012 -3.050032 180)
			(size 0.6096 1.4986)
			(layers "B.Cu" "B.Mask" "B.Paste")
			(net "GND")
		)
		(pad "18" smd rect
			(at -3.50012 3.050032 180)
			(size 0.6096 1.4986)
			(layers "B.Cu" "B.Mask" "B.Paste")
			(net "DRIVE_A_25_31_FLT_LED")
		)
		(pad "19" smd rect
			(at -4.500118 -3.050032 180)
			(size 0.6096 1.4986)
			(layers "B.Cu" "B.Mask" "B.Paste")
			(net "GND")
		)
		(pad "20" smd rect
			(at -4.500118 3.050032 180)
			(size 0.6096 1.4986)
			(layers "B.Cu" "B.Mask" "B.Paste")
			(net "DRIVE_A_25_31_ACT")
		)
		(pad "21" smd rect
			(at -6.500114 1.549908 180)
			(size 1.4986 2.0066)
			(layers "B.Cu" "B.Mask" "B.Paste")
			(net "GND")
		)
		(pad "22" smd rect
			(at 6.500114 1.549908 180)
			(size 1.4986 2.0066)
			(layers "B.Cu" "B.Mask" "B.Paste")
			(net "GND")
		)
		(zone
			(layer "B.Cu")
			(hatch none 0.5)
			(connect_pads
				(clearance 0)
			)
			(min_thickness 0.25)
			(keepout
				(tracks allowed)
				(vias not_allowed)
				(pads allowed)
				(copperpour not_allowed)
				(footprints allowed)
			)
			(placement
				(enabled no)
				(sheetname "")
			)
			(fill
				(thermal_gap 0.5)
				(thermal_bridge_width 0.5)
				(island_removal_mode 0)
			)
			(polygon
				(pts
					(xy 53.954934 -13.692632) (xy 44.345098 -13.692632) (xy 44.345098 -14.200632) (xy 53.954934 -14.200632)
				)
			)
		)
		(zone
			(layer "B.Cu")
			(hatch none 0.5)
			(connect_pads
				(clearance 0)
			)
			(min_thickness 0.25)
			(keepout
				(tracks allowed)
				(vias not_allowed)
				(pads allowed)
				(copperpour not_allowed)
				(footprints allowed)
			)
			(placement
				(enabled no)
				(sheetname "")
			)
			(fill
				(thermal_gap 0.5)
				(thermal_bridge_width 0.5)
				(island_removal_mode 0)
			)
			(polygon
				(pts
					(xy 53.954934 -9.599168) (xy 44.345098 -9.599168) (xy 44.345098 -14.200632) (xy 53.954934 -14.200632)
				)
			)
		)
		(zone
			(layer "B.Cu")
			(hatch none 0.5)
			(connect_pads
				(clearance 0)
			)
			(min_thickness 0.25)
			(keepout
				(tracks not_allowed)
				(vias allowed)
				(pads allowed)
				(copperpour not_allowed)
				(footprints allowed)
			)
			(placement
				(enabled no)
				(sheetname "")
			)
			(fill
				(thermal_gap 0.5)
				(thermal_bridge_width 0.5)
				(island_removal_mode 0)
			)
			(polygon
				(pts
					(xy 53.954934 -9.599168) (xy 44.345098 -9.599168) (xy 44.345098 -14.200632) (xy 53.954934 -14.200632)
				)
			)
		)
		(zone
			(layer "B.Cu")
			(hatch none 0.5)
			(connect_pads
				(clearance 0)
			)
			(min_thickness 0.25)
			(keepout
				(tracks allowed)
				(vias not_allowed)
				(pads allowed)
				(copperpour not_allowed)
				(footprints allowed)
			)
			(placement
				(enabled no)
				(sheetname "")
			)
			(fill
				(thermal_gap 0.5)
				(thermal_bridge_width 0.5)
				(island_removal_mode 0)
			)
			(polygon
				(pts
					(xy 53.954934 -9.599168) (xy 44.345098 -9.599168) (xy 44.345098 -10.107168) (xy 53.954934 -10.107168)
				)
			)
		)
	)
	(footprint ""
		(layer "B.Cu")
		(at 110.0074 -5.9182)
		(property "Reference" "Q8"
			(at 0 0 0)
			(layer "B.SilkS")
			(hide yes)
			(effects
				(font
					(size 1.27 1.27)
				)
				(justify mirror)
			)
		)
		(property "Value" "SSM3K324R-GP"
			(at -0.127 -8.9662 0)
			(unlocked yes)
			(layer "B.Fab")
			(hide yes)
			(effects
				(font
					(size 1.016 1.016)
					(thickness 0.1524)
				)
				(justify mirror)
			)
		)
		(property "Device Type" "SOT23DGS2D4H35"
			(at -0.127 -10.4902 0)
			(unlocked yes)
			(layer "B.Fab")
			(hide yes)
			(effects
				(font
					(size 1.016 1.016)
					(thickness 0.1524)
				)
				(justify mirror)
			)
		)
		(duplicate_pad_numbers_are_jumpers no)
		(fp_line
			(start -1.651 -1.778)
			(end 1.651 -1.778)
			(stroke
				(width 0.1524)
				(type default)
			)
			(layer "B.SilkS")
		)
		(fp_line
			(start -1.651 1.778)
			(end -1.651 -1.778)
			(stroke
				(width 0.1524)
				(type default)
			)
			(layer "B.SilkS")
		)
		(fp_line
			(start 1.651 -1.778)
			(end 1.651 1.778)
			(stroke
				(width 0.1524)
				(type default)
			)
			(layer "B.SilkS")
		)
		(fp_line
			(start 1.651 1.778)
			(end -1.651 1.778)
			(stroke
				(width 0.1524)
				(type default)
			)
			(layer "B.SilkS")
		)
		(fp_poly
			(pts
				(xy 1.778 1.8796) (xy 1.778 -1.8796) (xy -1.778 -1.8796) (xy -1.778 1.8796)
			)
			(stroke
				(width 0)
				(type default)
			)
			(fill no)
			(layer "B.CrtYd")
		)
		(fp_poly
			(pts
				(xy 1.778 1.8796) (xy 1.778 -1.8796) (xy -1.778 -1.8796) (xy -1.778 1.8796)
			)
			(stroke
				(width 0)
				(type default)
			)
			(fill no)
			(layer "B.Fab")
		)
		(pad "D" smd custom
			(at 0 -0.9525 180)
			(size 0.1905 0.1905)
			(layers "B.Cu" "B.Mask" "B.Paste")
			(net "DRV_ACT_27_33_N")
			(options
				(clearance outline)
				(anchor circle)
			)
			(primitives
				(gr_poly
					(pts
						(arc
							(start -0.1778 -0.5715)
							(mid -0.321484 -0.511984)
							(end -0.381 -0.3683)
						)
						(arc
							(start -0.381 0.3683)
							(mid -0.321484 0.511984)
							(end -0.1778 0.5715)
						)
						(arc
							(start 0.1778 0.5715)
							(mid 0.321484 0.511984)
							(end 0.381 0.3683)
						)
						(arc
							(start 0.381 -0.3683)
							(mid 0.321484 -0.511984)
							(end 0.1778 -0.5715)
						)
					)
					(width 0)
					(fill yes)
				)
			)
		)
		(pad "G" smd custom
			(at 0.98425 0.9525 180)
			(size 0.1905 0.1905)
			(layers "B.Cu" "B.Mask" "B.Paste")
			(net "DRIVE_A_27_33_ACT")
			(options
				(clearance outline)
				(anchor circle)
			)
			(primitives
				(gr_poly
					(pts
						(arc
							(start -0.1778 -0.5715)
							(mid -0.321484 -0.511984)
							(end -0.381 -0.3683)
						)
						(arc
							(start -0.381 0.3683)
							(mid -0.321484 0.511984)
							(end -0.1778 0.5715)
						)
						(arc
							(start 0.1778 0.5715)
							(mid 0.321484 0.511984)
							(end 0.381 0.3683)
						)
						(arc
							(start 0.381 -0.3683)
							(mid 0.321484 -0.511984)
							(end 0.1778 -0.5715)
						)
					)
					(width 0)
					(fill yes)
				)
			)
		)
		(pad "S" smd custom
			(at -0.98425 0.9525 180)
			(size 0.1905 0.1905)
			(layers "B.Cu" "B.Mask" "B.Paste")
			(net "GND")
			(options
				(clearance outline)
				(anchor circle)
			)
			(primitives
				(gr_poly
					(pts
						(arc
							(start -0.1778 -0.5715)
							(mid -0.321484 -0.511984)
							(end -0.381 -0.3683)
						)
						(arc
							(start -0.381 0.3683)
							(mid -0.321484 0.511984)
							(end -0.1778 0.5715)
						)
						(arc
							(start 0.1778 0.5715)
							(mid 0.321484 0.511984)
							(end 0.381 0.3683)
						)
						(arc
							(start 0.381 -0.3683)
							(mid 0.321484 -0.511984)
							(end 0.1778 -0.5715)
						)
					)
					(width 0)
					(fill yes)
				)
			)
		)
	)
	(footprint ""
		(layer "B.Cu")
		(at 38.735 -6.6802 -90)
		(property "Reference" "C1"
			(at 0 0 90)
			(layer "B.SilkS")
			(hide yes)
			(effects
				(font
					(size 1.27 1.27)
				)
				(justify mirror)
			)
		)
		(property "Value" "SC1U16V3KX-5GP"
			(at 0 -2.8194 270)
			(unlocked yes)
			(layer "B.Fab")
			(hide yes)
			(effects
				(font
					(size 1.016 1.016)
					(thickness 0.1524)
				)
				(justify mirror)
			)
		)
		(property "Device Type" "C603H36"
			(at 0 -4.3434 270)
			(unlocked yes)
			(layer "B.Fab")
			(hide yes)
			(effects
				(font
					(size 1.016 1.016)
					(thickness 0.1524)
				)
				(justify mirror)
			)
		)
		(duplicate_pad_numbers_are_jumpers no)
		(fp_line
			(start -0.508 0)
			(end 0.508 0)
			(stroke
				(width 0.2032)
				(type default)
			)
			(layer "B.SilkS")
		)
		(fp_rect
			(start 0.5842 1.3335)
			(end -0.5842 -1.3335)
			(stroke
				(width 0)
				(type default)
			)
			(fill no)
			(layer "B.CrtYd")
		)
		(fp_rect
			(start 0.5842 1.3335)
			(end -0.5842 -1.3335)
			(stroke
				(width 0)
				(type default)
			)
			(fill no)
			(layer "B.Fab")
		)
		(pad "1" smd custom
			(at 0 -0.762 90)
			(size 0.2159 0.2159)
			(layers "B.Cu" "B.Mask" "B.Paste")
			(net "P5V_A")
			(options
				(clearance outline)
				(anchor circle)
			)
			(primitives
				(gr_poly
					(pts
						(arc
							(start -0.3302 0.4318)
							(mid -0.402042 0.402042)
							(end -0.4318 0.3302)
						)
						(arc
							(start -0.4318 -0.3302)
							(mid -0.402042 -0.402042)
							(end -0.3302 -0.4318)
						)
						(arc
							(start 0.3302 -0.4318)
							(mid 0.402042 -0.402042)
							(end 0.4318 -0.3302)
						)
						(arc
							(start 0.4318 0.3302)
							(mid 0.402042 0.402042)
							(end 0.3302 0.4318)
						)
					)
					(width 0)
					(fill yes)
				)
			)
		)
		(pad "2" smd custom
			(at 0 0.762 90)
			(size 0.2159 0.2159)
			(layers "B.Cu" "B.Mask" "B.Paste")
			(net "GND")
			(options
				(clearance outline)
				(anchor circle)
			)
			(primitives
				(gr_poly
					(pts
						(arc
							(start -0.3302 0.4318)
							(mid -0.402042 0.402042)
							(end -0.4318 0.3302)
						)
						(arc
							(start -0.4318 -0.3302)
							(mid -0.402042 -0.402042)
							(end -0.3302 -0.4318)
						)
						(arc
							(start 0.3302 -0.4318)
							(mid 0.402042 -0.402042)
							(end 0.4318 -0.3302)
						)
						(arc
							(start 0.4318 0.3302)
							(mid 0.402042 0.402042)
							(end 0.3302 0.4318)
						)
					)
					(width 0)
					(fill yes)
				)
			)
		)
	)
	(footprint ""
		(layer "B.Cu")
		(at 136.0678 -5.9182 180)
		(property "Reference" "R9"
			(at 0 0 0)
			(layer "B.SilkS")
			(hide yes)
			(effects
				(font
					(size 1.27 1.27)
				)
				(justify mirror)
			)
		)
		(property "Value" "130R3F-GP"
			(at 0.0254 -2.5146 180)
			(unlocked yes)
			(layer "B.Fab")
			(hide yes)
			(effects
				(font
					(size 1.016 1.016)
					(thickness 0.1524)
				)
				(justify mirror)
			)
		)
		(property "Device Type" "R603H22"
			(at 0.0254 -4.0386 180)
			(unlocked yes)
			(layer "B.Fab")
			(hide yes)
			(effects
				(font
					(size 1.016 1.016)
					(thickness 0.1524)
				)
				(justify mirror)
			)
		)
		(duplicate_pad_numbers_are_jumpers no)
		(fp_line
			(start 0.4826 0)
			(end 0.2032 0)
			(stroke
				(width 0.2032)
				(type default)
			)
			(layer "B.SilkS")
		)
		(fp_line
			(start -0.2032 0)
			(end -0.4826 0)
			(stroke
				(width 0.2032)
				(type default)
			)
			(layer "B.SilkS")
		)
		(fp_rect
			(start 0.5842 1.3335)
			(end -0.5842 -1.3335)
			(stroke
				(width 0)
				(type default)
			)
			(fill no)
			(layer "B.CrtYd")
		)
		(fp_rect
			(start 0.5842 1.3335)
			(end -0.5842 -1.3335)
			(stroke
				(width 0)
				(type default)
			)
			(fill no)
			(layer "B.Fab")
		)
		(pad "1" smd custom
			(at 0 -0.762)
			(size 0.2159 0.2159)
			(layers "B.Cu" "B.Mask" "B.Paste")
			(net "P5V_A")
			(options
				(clearance outline)
				(anchor circle)
			)
			(primitives
				(gr_poly
					(pts
						(arc
							(start -0.3302 0.4318)
							(mid -0.402042 0.402042)
							(end -0.4318 0.3302)
						)
						(arc
							(start -0.4318 -0.3302)
							(mid -0.402042 -0.402042)
							(end -0.3302 -0.4318)
						)
						(arc
							(start 0.3302 -0.4318)
							(mid 0.402042 -0.402042)
							(end 0.4318 -0.3302)
						)
						(arc
							(start 0.4318 0.3302)
							(mid 0.402042 0.402042)
							(end 0.3302 0.4318)
						)
					)
					(width 0)
					(fill yes)
				)
			)
		)
		(pad "2" smd custom
			(at 0 0.762)
			(size 0.2159 0.2159)
			(layers "B.Cu" "B.Mask" "B.Paste")
			(net "FLT_HDD28_34")
			(options
				(clearance outline)
				(anchor circle)
			)
			(primitives
				(gr_poly
					(pts
						(arc
							(start -0.3302 0.4318)
							(mid -0.402042 0.402042)
							(end -0.4318 0.3302)
						)
						(arc
							(start -0.4318 -0.3302)
							(mid -0.402042 -0.402042)
							(end -0.3302 -0.4318)
						)
						(arc
							(start 0.3302 -0.4318)
							(mid 0.402042 -0.402042)
							(end 0.4318 -0.3302)
						)
						(arc
							(start 0.4318 0.3302)
							(mid 0.402042 0.402042)
							(end 0.3302 0.4318)
						)
					)
					(width 0)
					(fill yes)
				)
			)
		)
	)
	(footprint ""
		(layer "B.Cu")
		(at 29.6418 -2.6416 -90)
		(property "Reference" "R15"
			(at 0 0 90)
			(layer "B.SilkS")
			(hide yes)
			(effects
				(font
					(size 1.27 1.27)
				)
				(justify mirror)
			)
		)
		(property "Value" "4K7R2F-GP"
			(at -0.064008 -3.993896 270)
			(unlocked yes)
			(layer "B.Fab")
			(hide yes)
			(effects
				(font
					(size 1.016 1.016)
					(thickness 0.1524)
				)
				(justify mirror)
			)
		)
		(property "Device Type" "R402H16"
			(at -0.064008 -5.517896 270)
			(unlocked yes)
			(layer "B.Fab")
			(hide yes)
			(effects
				(font
					(size 1.016 1.016)
					(thickness 0.1524)
				)
				(justify mirror)
			)
		)
		(duplicate_pad_numbers_are_jumpers no)
		(fp_line
			(start -0.508 -0.9398)
			(end 0.508 -0.9398)
			(stroke
				(width 0.1524)
				(type default)
			)
			(layer "B.SilkS")
		)
		(fp_line
			(start 0.508 -0.9398)
			(end 0.508 0.9398)
			(stroke
				(width 0.1524)
				(type default)
			)
			(layer "B.SilkS")
		)
		(fp_rect
			(start 0.508 0.9398)
			(end -0.508 -0.9398)
			(stroke
				(width 0)
				(type default)
			)
			(fill no)
			(layer "B.CrtYd")
		)
		(fp_rect
			(start 0.508 0.9398)
			(end -0.508 -0.9398)
			(stroke
				(width 0)
				(type default)
			)
			(fill no)
			(layer "B.Fab")
		)
		(pad "1" smd custom
			(at 0 -0.4445 90)
			(size 0.1397 0.1397)
			(layers "B.Cu" "B.Mask" "B.Paste")
			(net "DRIVE_A_25_31_FLT_LED")
			(options
				(clearance outline)
				(anchor circle)
			)
			(primitives
				(gr_poly
					(pts
						(arc
							(start -0.1778 0.2794)
							(mid -0.249642 0.249642)
							(end -0.2794 0.1778)
						)
						(arc
							(start -0.2794 -0.1778)
							(mid -0.249642 -0.249642)
							(end -0.1778 -0.2794)
						)
						(arc
							(start 0.1778 -0.2794)
							(mid 0.249642 -0.249642)
							(end 0.2794 -0.1778)
						)
						(arc
							(start 0.2794 0.1778)
							(mid 0.249642 0.249642)
							(end 0.1778 0.2794)
						)
					)
					(width 0)
					(fill yes)
				)
			)
		)
		(pad "2" smd custom
			(at 0 0.4445 90)
			(size 0.1397 0.1397)
			(layers "B.Cu" "B.Mask" "B.Paste")
			(net "GND")
			(options
				(clearance outline)
				(anchor circle)
			)
			(primitives
				(gr_poly
					(pts
						(arc
							(start -0.1778 0.2794)
							(mid -0.249642 0.249642)
							(end -0.2794 0.1778)
						)
						(arc
							(start -0.2794 -0.1778)
							(mid -0.249642 -0.249642)
							(end -0.1778 -0.2794)
						)
						(arc
							(start 0.1778 -0.2794)
							(mid 0.249642 -0.249642)
							(end 0.2794 -0.1778)
						)
						(arc
							(start 0.2794 0.1778)
							(mid 0.249642 0.249642)
							(end 0.1778 0.2794)
						)
					)
					(width 0)
					(fill yes)
				)
			)
		)
	)
	(footprint ""
		(layer "B.Cu")
		(at 165.9636 -3.175 -90)
		(property "Reference" "R24"
			(at 0 0 90)
			(layer "B.SilkS")
			(hide yes)
			(effects
				(font
					(size 1.27 1.27)
				)
				(justify mirror)
			)
		)
		(property "Value" "4K7R2F-GP"
			(at -0.064008 -3.993896 270)
			(unlocked yes)
			(layer "B.Fab")
			(hide yes)
			(effects
				(font
					(size 1.016 1.016)
					(thickness 0.1524)
				)
				(justify mirror)
			)
		)
		(property "Device Type" "R402H16"
			(at -0.064008 -5.517896 270)
			(unlocked yes)
			(layer "B.Fab")
			(hide yes)
			(effects
				(font
					(size 1.016 1.016)
					(thickness 0.1524)
				)
				(justify mirror)
			)
		)
		(duplicate_pad_numbers_are_jumpers no)
		(fp_line
			(start -0.508 -0.9398)
			(end 0.508 -0.9398)
			(stroke
				(width 0.1524)
				(type default)
			)
			(layer "B.SilkS")
		)
		(fp_line
			(start 0.508 -0.9398)
			(end 0.508 0.9398)
			(stroke
				(width 0.1524)
				(type default)
			)
			(layer "B.SilkS")
		)
		(fp_rect
			(start 0.508 0.9398)
			(end -0.508 -0.9398)
			(stroke
				(width 0)
				(type default)
			)
			(fill no)
			(layer "B.CrtYd")
		)
		(fp_rect
			(start 0.508 0.9398)
			(end -0.508 -0.9398)
			(stroke
				(width 0)
				(type default)
			)
			(fill no)
			(layer "B.Fab")
		)
		(pad "1" smd custom
			(at 0 -0.4445 90)
			(size 0.1397 0.1397)
			(layers "B.Cu" "B.Mask" "B.Paste")
			(net "DRIVE_A_29_35_ACT")
			(options
				(clearance outline)
				(anchor circle)
			)
			(primitives
				(gr_poly
					(pts
						(arc
							(start -0.1778 0.2794)
							(mid -0.249642 0.249642)
							(end -0.2794 0.1778)
						)
						(arc
							(start -0.2794 -0.1778)
							(mid -0.249642 -0.249642)
							(end -0.1778 -0.2794)
						)
						(arc
							(start 0.1778 -0.2794)
							(mid 0.249642 -0.249642)
							(end 0.2794 -0.1778)
						)
						(arc
							(start 0.2794 0.1778)
							(mid 0.249642 0.249642)
							(end 0.1778 0.2794)
						)
					)
					(width 0)
					(fill yes)
				)
			)
		)
		(pad "2" smd custom
			(at 0 0.4445 90)
			(size 0.1397 0.1397)
			(layers "B.Cu" "B.Mask" "B.Paste")
			(net "GND")
			(options
				(clearance outline)
				(anchor circle)
			)
			(primitives
				(gr_poly
					(pts
						(arc
							(start -0.1778 0.2794)
							(mid -0.249642 0.249642)
							(end -0.2794 0.1778)
						)
						(arc
							(start -0.2794 -0.1778)
							(mid -0.249642 -0.249642)
							(end -0.1778 -0.2794)
						)
						(arc
							(start 0.1778 -0.2794)
							(mid 0.249642 -0.249642)
							(end 0.2794 -0.1778)
						)
						(arc
							(start 0.2794 0.1778)
							(mid 0.249642 0.249642)
							(end 0.1778 0.2794)
						)
					)
					(width 0)
					(fill yes)
				)
			)
		)
	)
	(footprint ""
		(layer "B.Cu")
		(at 22.8854 -2.9972 -90)
		(property "Reference" "R14"
			(at 0 0 90)
			(layer "B.SilkS")
			(hide yes)
			(effects
				(font
					(size 1.27 1.27)
				)
				(justify mirror)
			)
		)
		(property "Value" "4K7R2F-GP"
			(at -0.064008 -3.993896 270)
			(unlocked yes)
			(layer "B.Fab")
			(hide yes)
			(effects
				(font
					(size 1.016 1.016)
					(thickness 0.1524)
				)
				(justify mirror)
			)
		)
		(property "Device Type" "R402H16"
			(at -0.064008 -5.517896 270)
			(unlocked yes)
			(layer "B.Fab")
			(hide yes)
			(effects
				(font
					(size 1.016 1.016)
					(thickness 0.1524)
				)
				(justify mirror)
			)
		)
		(duplicate_pad_numbers_are_jumpers no)
		(fp_line
			(start -0.508 -0.9398)
			(end 0.508 -0.9398)
			(stroke
				(width 0.1524)
				(type default)
			)
			(layer "B.SilkS")
		)
		(fp_line
			(start 0.508 -0.9398)
			(end 0.508 0.9398)
			(stroke
				(width 0.1524)
				(type default)
			)
			(layer "B.SilkS")
		)
		(fp_rect
			(start 0.508 0.9398)
			(end -0.508 -0.9398)
			(stroke
				(width 0)
				(type default)
			)
			(fill no)
			(layer "B.CrtYd")
		)
		(fp_rect
			(start 0.508 0.9398)
			(end -0.508 -0.9398)
			(stroke
				(width 0)
				(type default)
			)
			(fill no)
			(layer "B.Fab")
		)
		(pad "1" smd custom
			(at 0 -0.4445 90)
			(size 0.1397 0.1397)
			(layers "B.Cu" "B.Mask" "B.Paste")
			(net "DRIVE_A_24_30_ACT")
			(options
				(clearance outline)
				(anchor circle)
			)
			(primitives
				(gr_poly
					(pts
						(arc
							(start -0.1778 0.2794)
							(mid -0.249642 0.249642)
							(end -0.2794 0.1778)
						)
						(arc
							(start -0.2794 -0.1778)
							(mid -0.249642 -0.249642)
							(end -0.1778 -0.2794)
						)
						(arc
							(start 0.1778 -0.2794)
							(mid 0.249642 -0.249642)
							(end 0.2794 -0.1778)
						)
						(arc
							(start 0.2794 0.1778)
							(mid 0.249642 0.249642)
							(end 0.1778 0.2794)
						)
					)
					(width 0)
					(fill yes)
				)
			)
		)
		(pad "2" smd custom
			(at 0 0.4445 90)
			(size 0.1397 0.1397)
			(layers "B.Cu" "B.Mask" "B.Paste")
			(net "GND")
			(options
				(clearance outline)
				(anchor circle)
			)
			(primitives
				(gr_poly
					(pts
						(arc
							(start -0.1778 0.2794)
							(mid -0.249642 0.249642)
							(end -0.2794 0.1778)
						)
						(arc
							(start -0.2794 -0.1778)
							(mid -0.249642 -0.249642)
							(end -0.1778 -0.2794)
						)
						(arc
							(start 0.1778 -0.2794)
							(mid 0.249642 -0.249642)
							(end 0.2794 -0.1778)
						)
						(arc
							(start 0.2794 0.1778)
							(mid 0.249642 0.249642)
							(end 0.1778 0.2794)
						)
					)
					(width 0)
					(fill yes)
				)
			)
		)
	)
	(footprint ""
		(layer "B.Cu")
		(at 64.797178 -5.652516)
		(property "Reference" "Q6"
			(at 0 0 0)
			(layer "B.SilkS")
			(hide yes)
			(effects
				(font
					(size 1.27 1.27)
				)
				(justify mirror)
			)
		)
		(property "Value" "SSM3K324R-GP"
			(at -0.127 -8.9662 0)
			(unlocked yes)
			(layer "B.Fab")
			(hide yes)
			(effects
				(font
					(size 1.016 1.016)
					(thickness 0.1524)
				)
				(justify mirror)
			)
		)
		(property "Device Type" "SOT23DGS2D4H35"
			(at -0.127 -10.4902 0)
			(unlocked yes)
			(layer "B.Fab")
			(hide yes)
			(effects
				(font
					(size 1.016 1.016)
					(thickness 0.1524)
				)
				(justify mirror)
			)
		)
		(duplicate_pad_numbers_are_jumpers no)
		(fp_line
			(start -1.651 -1.778)
			(end 1.651 -1.778)
			(stroke
				(width 0.1524)
				(type default)
			)
			(layer "B.SilkS")
		)
		(fp_line
			(start -1.651 1.778)
			(end -1.651 -1.778)
			(stroke
				(width 0.1524)
				(type default)
			)
			(layer "B.SilkS")
		)
		(fp_line
			(start 1.651 -1.778)
			(end 1.651 1.778)
			(stroke
				(width 0.1524)
				(type default)
			)
			(layer "B.SilkS")
		)
		(fp_line
			(start 1.651 1.778)
			(end -1.651 1.778)
			(stroke
				(width 0.1524)
				(type default)
			)
			(layer "B.SilkS")
		)
		(fp_poly
			(pts
				(xy 1.778 1.8796) (xy 1.778 -1.8796) (xy -1.778 -1.8796) (xy -1.778 1.8796)
			)
			(stroke
				(width 0)
				(type default)
			)
			(fill no)
			(layer "B.CrtYd")
		)
		(fp_poly
			(pts
				(xy 1.778 1.8796) (xy 1.778 -1.8796) (xy -1.778 -1.8796) (xy -1.778 1.8796)
			)
			(stroke
				(width 0)
				(type default)
			)
			(fill no)
			(layer "B.Fab")
		)
		(pad "D" smd custom
			(at 0 -0.9525 180)
			(size 0.1905 0.1905)
			(layers "B.Cu" "B.Mask" "B.Paste")
			(net "DRV_ACT_26_32_N")
			(options
				(clearance outline)
				(anchor circle)
			)
			(primitives
				(gr_poly
					(pts
						(arc
							(start -0.1778 -0.5715)
							(mid -0.321484 -0.511984)
							(end -0.381 -0.3683)
						)
						(arc
							(start -0.381 0.3683)
							(mid -0.321484 0.511984)
							(end -0.1778 0.5715)
						)
						(arc
							(start 0.1778 0.5715)
							(mid 0.321484 0.511984)
							(end 0.381 0.3683)
						)
						(arc
							(start 0.381 -0.3683)
							(mid 0.321484 -0.511984)
							(end 0.1778 -0.5715)
						)
					)
					(width 0)
					(fill yes)
				)
			)
		)
		(pad "G" smd custom
			(at 0.98425 0.9525 180)
			(size 0.1905 0.1905)
			(layers "B.Cu" "B.Mask" "B.Paste")
			(net "DRIVE_A_26_32_ACT")
			(options
				(clearance outline)
				(anchor circle)
			)
			(primitives
				(gr_poly
					(pts
						(arc
							(start -0.1778 -0.5715)
							(mid -0.321484 -0.511984)
							(end -0.381 -0.3683)
						)
						(arc
							(start -0.381 0.3683)
							(mid -0.321484 0.511984)
							(end -0.1778 0.5715)
						)
						(arc
							(start 0.1778 0.5715)
							(mid 0.321484 0.511984)
							(end 0.381 0.3683)
						)
						(arc
							(start 0.381 -0.3683)
							(mid 0.321484 -0.511984)
							(end 0.1778 -0.5715)
						)
					)
					(width 0)
					(fill yes)
				)
			)
		)
		(pad "S" smd custom
			(at -0.98425 0.9525 180)
			(size 0.1905 0.1905)
			(layers "B.Cu" "B.Mask" "B.Paste")
			(net "GND")
			(options
				(clearance outline)
				(anchor circle)
			)
			(primitives
				(gr_poly
					(pts
						(arc
							(start -0.1778 -0.5715)
							(mid -0.321484 -0.511984)
							(end -0.381 -0.3683)
						)
						(arc
							(start -0.381 0.3683)
							(mid -0.321484 0.511984)
							(end -0.1778 0.5715)
						)
						(arc
							(start 0.1778 0.5715)
							(mid 0.321484 0.511984)
							(end 0.381 0.3683)
						)
						(arc
							(start 0.381 -0.3683)
							(mid 0.321484 -0.511984)
							(end 0.1778 -0.5715)
						)
					)
					(width 0)
					(fill yes)
				)
			)
		)
	)
	(footprint ""
		(layer "B.Cu")
		(at 68.636388 -3.247644 -90)
		(property "Reference" "R17"
			(at 0 0 90)
			(layer "B.SilkS")
			(hide yes)
			(effects
				(font
					(size 1.27 1.27)
				)
				(justify mirror)
			)
		)
		(property "Value" "4K7R2F-GP"
			(at -0.064008 -3.993896 270)
			(unlocked yes)
			(layer "B.Fab")
			(hide yes)
			(effects
				(font
					(size 1.016 1.016)
					(thickness 0.1524)
				)
				(justify mirror)
			)
		)
		(property "Device Type" "R402H16"
			(at -0.064008 -5.517896 270)
			(unlocked yes)
			(layer "B.Fab")
			(hide yes)
			(effects
				(font
					(size 1.016 1.016)
					(thickness 0.1524)
				)
				(justify mirror)
			)
		)
		(duplicate_pad_numbers_are_jumpers no)
		(fp_line
			(start -0.508 -0.9398)
			(end 0.508 -0.9398)
			(stroke
				(width 0.1524)
				(type default)
			)
			(layer "B.SilkS")
		)
		(fp_line
			(start 0.508 -0.9398)
			(end 0.508 0.9398)
			(stroke
				(width 0.1524)
				(type default)
			)
			(layer "B.SilkS")
		)
		(fp_rect
			(start 0.508 0.9398)
			(end -0.508 -0.9398)
			(stroke
				(width 0)
				(type default)
			)
			(fill no)
			(layer "B.CrtYd")
		)
		(fp_rect
			(start 0.508 0.9398)
			(end -0.508 -0.9398)
			(stroke
				(width 0)
				(type default)
			)
			(fill no)
			(layer "B.Fab")
		)
		(pad "1" smd custom
			(at 0 -0.4445 90)
			(size 0.1397 0.1397)
			(layers "B.Cu" "B.Mask" "B.Paste")
			(net "DRIVE_A_26_32_FLT_LED")
			(options
				(clearance outline)
				(anchor circle)
			)
			(primitives
				(gr_poly
					(pts
						(arc
							(start -0.1778 0.2794)
							(mid -0.249642 0.249642)
							(end -0.2794 0.1778)
						)
						(arc
							(start -0.2794 -0.1778)
							(mid -0.249642 -0.249642)
							(end -0.1778 -0.2794)
						)
						(arc
							(start 0.1778 -0.2794)
							(mid 0.249642 -0.249642)
							(end 0.2794 -0.1778)
						)
						(arc
							(start 0.2794 0.1778)
							(mid 0.249642 0.249642)
							(end 0.1778 0.2794)
						)
					)
					(width 0)
					(fill yes)
				)
			)
		)
		(pad "2" smd custom
			(at 0 0.4445 90)
			(size 0.1397 0.1397)
			(layers "B.Cu" "B.Mask" "B.Paste")
			(net "GND")
			(options
				(clearance outline)
				(anchor circle)
			)
			(primitives
				(gr_poly
					(pts
						(arc
							(start -0.1778 0.2794)
							(mid -0.249642 0.249642)
							(end -0.2794 0.1778)
						)
						(arc
							(start -0.2794 -0.1778)
							(mid -0.249642 -0.249642)
							(end -0.1778 -0.2794)
						)
						(arc
							(start 0.1778 -0.2794)
							(mid 0.249642 -0.249642)
							(end 0.2794 -0.1778)
						)
						(arc
							(start 0.2794 0.1778)
							(mid 0.249642 0.249642)
							(end 0.1778 0.2794)
						)
					)
					(width 0)
					(fill yes)
				)
			)
		)
	)
	(footprint ""
		(layer "B.Cu")
		(at 103.9876 -6.0198 180)
		(property "Reference" "R7"
			(at 0 0 0)
			(layer "B.SilkS")
			(hide yes)
			(effects
				(font
					(size 1.27 1.27)
				)
				(justify mirror)
			)
		)
		(property "Value" "130R3F-GP"
			(at 0.0254 -2.5146 180)
			(unlocked yes)
			(layer "B.Fab")
			(hide yes)
			(effects
				(font
					(size 1.016 1.016)
					(thickness 0.1524)
				)
				(justify mirror)
			)
		)
		(property "Device Type" "R603H22"
			(at 0.0254 -4.0386 180)
			(unlocked yes)
			(layer "B.Fab")
			(hide yes)
			(effects
				(font
					(size 1.016 1.016)
					(thickness 0.1524)
				)
				(justify mirror)
			)
		)
		(duplicate_pad_numbers_are_jumpers no)
		(fp_line
			(start 0.4826 0)
			(end 0.2032 0)
			(stroke
				(width 0.2032)
				(type default)
			)
			(layer "B.SilkS")
		)
		(fp_line
			(start -0.2032 0)
			(end -0.4826 0)
			(stroke
				(width 0.2032)
				(type default)
			)
			(layer "B.SilkS")
		)
		(fp_rect
			(start 0.5842 1.3335)
			(end -0.5842 -1.3335)
			(stroke
				(width 0)
				(type default)
			)
			(fill no)
			(layer "B.CrtYd")
		)
		(fp_rect
			(start 0.5842 1.3335)
			(end -0.5842 -1.3335)
			(stroke
				(width 0)
				(type default)
			)
			(fill no)
			(layer "B.Fab")
		)
		(pad "1" smd custom
			(at 0 -0.762)
			(size 0.2159 0.2159)
			(layers "B.Cu" "B.Mask" "B.Paste")
			(net "P5V_A")
			(options
				(clearance outline)
				(anchor circle)
			)
			(primitives
				(gr_poly
					(pts
						(arc
							(start -0.3302 0.4318)
							(mid -0.402042 0.402042)
							(end -0.4318 0.3302)
						)
						(arc
							(start -0.4318 -0.3302)
							(mid -0.402042 -0.402042)
							(end -0.3302 -0.4318)
						)
						(arc
							(start 0.3302 -0.4318)
							(mid 0.402042 -0.402042)
							(end 0.4318 -0.3302)
						)
						(arc
							(start 0.4318 0.3302)
							(mid 0.402042 0.402042)
							(end 0.3302 0.4318)
						)
					)
					(width 0)
					(fill yes)
				)
			)
		)
		(pad "2" smd custom
			(at 0 0.762)
			(size 0.2159 0.2159)
			(layers "B.Cu" "B.Mask" "B.Paste")
			(net "FLT_HDD27_33")
			(options
				(clearance outline)
				(anchor circle)
			)
			(primitives
				(gr_poly
					(pts
						(arc
							(start -0.3302 0.4318)
							(mid -0.402042 0.402042)
							(end -0.4318 0.3302)
						)
						(arc
							(start -0.4318 -0.3302)
							(mid -0.402042 -0.402042)
							(end -0.3302 -0.4318)
						)
						(arc
							(start 0.3302 -0.4318)
							(mid 0.402042 -0.402042)
							(end 0.4318 -0.3302)
						)
						(arc
							(start 0.4318 0.3302)
							(mid 0.402042 0.402042)
							(end 0.3302 0.4318)
						)
					)
					(width 0)
					(fill yes)
				)
			)
		)
	)
	(footprint ""
		(layer "B.Cu")
		(at 24.6888 -5.9436 180)
		(property "Reference" "R2"
			(at 0 0 0)
			(layer "B.SilkS")
			(hide yes)
			(effects
				(font
					(size 1.27 1.27)
				)
				(justify mirror)
			)
		)
		(property "Value" "91R3F-1-GP"
			(at 0.0254 -2.5146 180)
			(unlocked yes)
			(layer "B.Fab")
			(hide yes)
			(effects
				(font
					(size 1.016 1.016)
					(thickness 0.1524)
				)
				(justify mirror)
			)
		)
		(property "Device Type" "R603H22"
			(at 0.0254 -4.0386 180)
			(unlocked yes)
			(layer "B.Fab")
			(hide yes)
			(effects
				(font
					(size 1.016 1.016)
					(thickness 0.1524)
				)
				(justify mirror)
			)
		)
		(duplicate_pad_numbers_are_jumpers no)
		(fp_line
			(start 0.4826 0)
			(end 0.2032 0)
			(stroke
				(width 0.2032)
				(type default)
			)
			(layer "B.SilkS")
		)
		(fp_line
			(start -0.2032 0)
			(end -0.4826 0)
			(stroke
				(width 0.2032)
				(type default)
			)
			(layer "B.SilkS")
		)
		(fp_rect
			(start 0.5842 1.3335)
			(end -0.5842 -1.3335)
			(stroke
				(width 0)
				(type default)
			)
			(fill no)
			(layer "B.CrtYd")
		)
		(fp_rect
			(start 0.5842 1.3335)
			(end -0.5842 -1.3335)
			(stroke
				(width 0)
				(type default)
			)
			(fill no)
			(layer "B.Fab")
		)
		(pad "1" smd custom
			(at 0 -0.762)
			(size 0.2159 0.2159)
			(layers "B.Cu" "B.Mask" "B.Paste")
			(net "P5V_A")
			(options
				(clearance outline)
				(anchor circle)
			)
			(primitives
				(gr_poly
					(pts
						(arc
							(start -0.3302 0.4318)
							(mid -0.402042 0.402042)
							(end -0.4318 0.3302)
						)
						(arc
							(start -0.4318 -0.3302)
							(mid -0.402042 -0.402042)
							(end -0.3302 -0.4318)
						)
						(arc
							(start 0.3302 -0.4318)
							(mid 0.402042 -0.402042)
							(end 0.4318 -0.3302)
						)
						(arc
							(start 0.4318 0.3302)
							(mid 0.402042 0.402042)
							(end 0.3302 0.4318)
						)
					)
					(width 0)
					(fill yes)
				)
			)
		)
		(pad "2" smd custom
			(at 0 0.762)
			(size 0.2159 0.2159)
			(layers "B.Cu" "B.Mask" "B.Paste")
			(net "DRV_ACT_24_30")
			(options
				(clearance outline)
				(anchor circle)
			)
			(primitives
				(gr_poly
					(pts
						(arc
							(start -0.3302 0.4318)
							(mid -0.402042 0.402042)
							(end -0.4318 0.3302)
						)
						(arc
							(start -0.4318 -0.3302)
							(mid -0.402042 -0.402042)
							(end -0.3302 -0.4318)
						)
						(arc
							(start 0.3302 -0.4318)
							(mid 0.402042 -0.402042)
							(end 0.4318 -0.3302)
						)
						(arc
							(start 0.4318 0.3302)
							(mid 0.402042 0.402042)
							(end 0.3302 0.4318)
						)
					)
					(width 0)
					(fill yes)
				)
			)
		)
	)
	(footprint ""
		(layer "B.Cu")
		(at 161.925 -5.588)
		(property "Reference" "Q11"
			(at 0 0 0)
			(layer "B.SilkS")
			(hide yes)
			(effects
				(font
					(size 1.27 1.27)
				)
				(justify mirror)
			)
		)
		(property "Value" "2N7002K-2-GP"
			(at -0.127 -8.9662 0)
			(unlocked yes)
			(layer "B.Fab")
			(hide yes)
			(effects
				(font
					(size 1.016 1.016)
					(thickness 0.1524)
				)
				(justify mirror)
			)
		)
		(property "Device Type" "SOT23DGS2D4H44"
			(at -0.127 -10.4902 0)
			(unlocked yes)
			(layer "B.Fab")
			(hide yes)
			(effects
				(font
					(size 1.016 1.016)
					(thickness 0.1524)
				)
				(justify mirror)
			)
		)
		(duplicate_pad_numbers_are_jumpers no)
		(fp_line
			(start -1.651 -1.778)
			(end 1.651 -1.778)
			(stroke
				(width 0.1524)
				(type default)
			)
			(layer "B.SilkS")
		)
		(fp_line
			(start -1.651 1.778)
			(end -1.651 -1.778)
			(stroke
				(width 0.1524)
				(type default)
			)
			(layer "B.SilkS")
		)
		(fp_line
			(start 1.651 -1.778)
			(end 1.651 1.778)
			(stroke
				(width 0.1524)
				(type default)
			)
			(layer "B.SilkS")
		)
		(fp_line
			(start 1.651 1.778)
			(end -1.651 1.778)
			(stroke
				(width 0.1524)
				(type default)
			)
			(layer "B.SilkS")
		)
		(fp_poly
			(pts
				(xy 1.778 1.8796) (xy 1.778 -1.8796) (xy -1.778 -1.8796) (xy -1.778 1.8796)
			)
			(stroke
				(width 0)
				(type default)
			)
			(fill no)
			(layer "B.CrtYd")
		)
		(fp_poly
			(pts
				(xy 1.778 1.8796) (xy 1.778 -1.8796) (xy -1.778 -1.8796) (xy -1.778 1.8796)
			)
			(stroke
				(width 0)
				(type default)
			)
			(fill no)
			(layer "B.Fab")
		)
		(pad "D" smd custom
			(at 0 -0.9525 180)
			(size 0.1905 0.1905)
			(layers "B.Cu" "B.Mask" "B.Paste")
			(net "FLT_HDD29_35_N")
			(options
				(clearance outline)
				(anchor circle)
			)
			(primitives
				(gr_poly
					(pts
						(arc
							(start -0.1778 -0.5715)
							(mid -0.321484 -0.511984)
							(end -0.381 -0.3683)
						)
						(arc
							(start -0.381 0.3683)
							(mid -0.321484 0.511984)
							(end -0.1778 0.5715)
						)
						(arc
							(start 0.1778 0.5715)
							(mid 0.321484 0.511984)
							(end 0.381 0.3683)
						)
						(arc
							(start 0.381 -0.3683)
							(mid 0.321484 -0.511984)
							(end 0.1778 -0.5715)
						)
					)
					(width 0)
					(fill yes)
				)
			)
		)
		(pad "G" smd custom
			(at 0.98425 0.9525 180)
			(size 0.1905 0.1905)
			(layers "B.Cu" "B.Mask" "B.Paste")
			(net "DRIVE_A_29_35_FLT_LED")
			(options
				(clearance outline)
				(anchor circle)
			)
			(primitives
				(gr_poly
					(pts
						(arc
							(start -0.1778 -0.5715)
							(mid -0.321484 -0.511984)
							(end -0.381 -0.3683)
						)
						(arc
							(start -0.381 0.3683)
							(mid -0.321484 0.511984)
							(end -0.1778 0.5715)
						)
						(arc
							(start 0.1778 0.5715)
							(mid 0.321484 0.511984)
							(end 0.381 0.3683)
						)
						(arc
							(start 0.381 -0.3683)
							(mid 0.321484 -0.511984)
							(end 0.1778 -0.5715)
						)
					)
					(width 0)
					(fill yes)
				)
			)
		)
		(pad "S" smd custom
			(at -0.98425 0.9525 180)
			(size 0.1905 0.1905)
			(layers "B.Cu" "B.Mask" "B.Paste")
			(net "GND")
			(options
				(clearance outline)
				(anchor circle)
			)
			(primitives
				(gr_poly
					(pts
						(arc
							(start -0.1778 -0.5715)
							(mid -0.321484 -0.511984)
							(end -0.381 -0.3683)
						)
						(arc
							(start -0.381 0.3683)
							(mid -0.321484 0.511984)
							(end -0.1778 0.5715)
						)
						(arc
							(start 0.1778 0.5715)
							(mid 0.321484 0.511984)
							(end 0.381 0.3683)
						)
						(arc
							(start 0.381 -0.3683)
							(mid 0.321484 -0.511984)
							(end 0.1778 -0.5715)
						)
					)
					(width 0)
					(fill yes)
				)
			)
		)
	)
	(footprint ""
		(layer "B.Cu")
		(at 62.421262 -6.201918 180)
		(property "Reference" "R5"
			(at 0 0 0)
			(layer "B.SilkS")
			(hide yes)
			(effects
				(font
					(size 1.27 1.27)
				)
				(justify mirror)
			)
		)
		(property "Value" "130R3F-GP"
			(at 0.0254 -2.5146 180)
			(unlocked yes)
			(layer "B.Fab")
			(hide yes)
			(effects
				(font
					(size 1.016 1.016)
					(thickness 0.1524)
				)
				(justify mirror)
			)
		)
		(property "Device Type" "R603H22"
			(at 0.0254 -4.0386 180)
			(unlocked yes)
			(layer "B.Fab")
			(hide yes)
			(effects
				(font
					(size 1.016 1.016)
					(thickness 0.1524)
				)
				(justify mirror)
			)
		)
		(duplicate_pad_numbers_are_jumpers no)
		(fp_line
			(start 0.4826 0)
			(end 0.2032 0)
			(stroke
				(width 0.2032)
				(type default)
			)
			(layer "B.SilkS")
		)
		(fp_line
			(start -0.2032 0)
			(end -0.4826 0)
			(stroke
				(width 0.2032)
				(type default)
			)
			(layer "B.SilkS")
		)
		(fp_rect
			(start 0.5842 1.3335)
			(end -0.5842 -1.3335)
			(stroke
				(width 0)
				(type default)
			)
			(fill no)
			(layer "B.CrtYd")
		)
		(fp_rect
			(start 0.5842 1.3335)
			(end -0.5842 -1.3335)
			(stroke
				(width 0)
				(type default)
			)
			(fill no)
			(layer "B.Fab")
		)
		(pad "1" smd custom
			(at 0 -0.762)
			(size 0.2159 0.2159)
			(layers "B.Cu" "B.Mask" "B.Paste")
			(net "P5V_A")
			(options
				(clearance outline)
				(anchor circle)
			)
			(primitives
				(gr_poly
					(pts
						(arc
							(start -0.3302 0.4318)
							(mid -0.402042 0.402042)
							(end -0.4318 0.3302)
						)
						(arc
							(start -0.4318 -0.3302)
							(mid -0.402042 -0.402042)
							(end -0.3302 -0.4318)
						)
						(arc
							(start 0.3302 -0.4318)
							(mid 0.402042 -0.402042)
							(end 0.4318 -0.3302)
						)
						(arc
							(start 0.4318 0.3302)
							(mid 0.402042 0.402042)
							(end 0.3302 0.4318)
						)
					)
					(width 0)
					(fill yes)
				)
			)
		)
		(pad "2" smd custom
			(at 0 0.762)
			(size 0.2159 0.2159)
			(layers "B.Cu" "B.Mask" "B.Paste")
			(net "FLT_HDD26_32")
			(options
				(clearance outline)
				(anchor circle)
			)
			(primitives
				(gr_poly
					(pts
						(arc
							(start -0.3302 0.4318)
							(mid -0.402042 0.402042)
							(end -0.4318 0.3302)
						)
						(arc
							(start -0.4318 -0.3302)
							(mid -0.402042 -0.402042)
							(end -0.3302 -0.4318)
						)
						(arc
							(start 0.3302 -0.4318)
							(mid 0.402042 -0.402042)
							(end 0.4318 -0.3302)
						)
						(arc
							(start 0.4318 0.3302)
							(mid 0.402042 0.402042)
							(end 0.3302 0.4318)
						)
					)
					(width 0)
					(fill yes)
				)
			)
		)
	)
	(footprint ""
		(layer "B.Cu")
		(at 106.6292 -3.5052 -90)
		(property "Reference" "R19"
			(at 0 0 90)
			(layer "B.SilkS")
			(hide yes)
			(effects
				(font
					(size 1.27 1.27)
				)
				(justify mirror)
			)
		)
		(property "Value" "4K7R2F-GP"
			(at -0.064008 -3.993896 270)
			(unlocked yes)
			(layer "B.Fab")
			(hide yes)
			(effects
				(font
					(size 1.016 1.016)
					(thickness 0.1524)
				)
				(justify mirror)
			)
		)
		(property "Device Type" "R402H16"
			(at -0.064008 -5.517896 270)
			(unlocked yes)
			(layer "B.Fab")
			(hide yes)
			(effects
				(font
					(size 1.016 1.016)
					(thickness 0.1524)
				)
				(justify mirror)
			)
		)
		(duplicate_pad_numbers_are_jumpers no)
		(fp_line
			(start -0.508 -0.9398)
			(end 0.508 -0.9398)
			(stroke
				(width 0.1524)
				(type default)
			)
			(layer "B.SilkS")
		)
		(fp_line
			(start 0.508 -0.9398)
			(end 0.508 0.9398)
			(stroke
				(width 0.1524)
				(type default)
			)
			(layer "B.SilkS")
		)
		(fp_rect
			(start 0.508 0.9398)
			(end -0.508 -0.9398)
			(stroke
				(width 0)
				(type default)
			)
			(fill no)
			(layer "B.CrtYd")
		)
		(fp_rect
			(start 0.508 0.9398)
			(end -0.508 -0.9398)
			(stroke
				(width 0)
				(type default)
			)
			(fill no)
			(layer "B.Fab")
		)
		(pad "1" smd custom
			(at 0 -0.4445 90)
			(size 0.1397 0.1397)
			(layers "B.Cu" "B.Mask" "B.Paste")
			(net "DRIVE_A_27_33_FLT_LED")
			(options
				(clearance outline)
				(anchor circle)
			)
			(primitives
				(gr_poly
					(pts
						(arc
							(start -0.1778 0.2794)
							(mid -0.249642 0.249642)
							(end -0.2794 0.1778)
						)
						(arc
							(start -0.2794 -0.1778)
							(mid -0.249642 -0.249642)
							(end -0.1778 -0.2794)
						)
						(arc
							(start 0.1778 -0.2794)
							(mid 0.249642 -0.249642)
							(end 0.2794 -0.1778)
						)
						(arc
							(start 0.2794 0.1778)
							(mid 0.249642 0.249642)
							(end 0.1778 0.2794)
						)
					)
					(width 0)
					(fill yes)
				)
			)
		)
		(pad "2" smd custom
			(at 0 0.4445 90)
			(size 0.1397 0.1397)
			(layers "B.Cu" "B.Mask" "B.Paste")
			(net "GND")
			(options
				(clearance outline)
				(anchor circle)
			)
			(primitives
				(gr_poly
					(pts
						(arc
							(start -0.1778 0.2794)
							(mid -0.249642 0.249642)
							(end -0.2794 0.1778)
						)
						(arc
							(start -0.2794 -0.1778)
							(mid -0.249642 -0.249642)
							(end -0.1778 -0.2794)
						)
						(arc
							(start 0.1778 -0.2794)
							(mid 0.249642 -0.249642)
							(end 0.2794 -0.1778)
						)
						(arc
							(start 0.2794 0.1778)
							(mid 0.249642 0.249642)
							(end 0.1778 0.2794)
						)
					)
					(width 0)
					(fill yes)
				)
			)
		)
	)
	(footprint ""
		(layer "B.Cu")
		(at 28.448 -5.0546)
		(property "Reference" "Q3"
			(at 0 0 0)
			(layer "B.SilkS")
			(hide yes)
			(effects
				(font
					(size 1.27 1.27)
				)
				(justify mirror)
			)
		)
		(property "Value" "2N7002K-2-GP"
			(at -0.127 -8.9662 0)
			(unlocked yes)
			(layer "B.Fab")
			(hide yes)
			(effects
				(font
					(size 1.016 1.016)
					(thickness 0.1524)
				)
				(justify mirror)
			)
		)
		(property "Device Type" "SOT23DGS2D4H44"
			(at -0.127 -10.4902 0)
			(unlocked yes)
			(layer "B.Fab")
			(hide yes)
			(effects
				(font
					(size 1.016 1.016)
					(thickness 0.1524)
				)
				(justify mirror)
			)
		)
		(duplicate_pad_numbers_are_jumpers no)
		(fp_line
			(start -1.651 -1.778)
			(end 1.651 -1.778)
			(stroke
				(width 0.1524)
				(type default)
			)
			(layer "B.SilkS")
		)
		(fp_line
			(start -1.651 1.778)
			(end -1.651 -1.778)
			(stroke
				(width 0.1524)
				(type default)
			)
			(layer "B.SilkS")
		)
		(fp_line
			(start 1.651 -1.778)
			(end 1.651 1.778)
			(stroke
				(width 0.1524)
				(type default)
			)
			(layer "B.SilkS")
		)
		(fp_line
			(start 1.651 1.778)
			(end -1.651 1.778)
			(stroke
				(width 0.1524)
				(type default)
			)
			(layer "B.SilkS")
		)
		(fp_poly
			(pts
				(xy 1.778 1.8796) (xy 1.778 -1.8796) (xy -1.778 -1.8796) (xy -1.778 1.8796)
			)
			(stroke
				(width 0)
				(type default)
			)
			(fill no)
			(layer "B.CrtYd")
		)
		(fp_poly
			(pts
				(xy 1.778 1.8796) (xy 1.778 -1.8796) (xy -1.778 -1.8796) (xy -1.778 1.8796)
			)
			(stroke
				(width 0)
				(type default)
			)
			(fill no)
			(layer "B.Fab")
		)
		(pad "D" smd custom
			(at 0 -0.9525 180)
			(size 0.1905 0.1905)
			(layers "B.Cu" "B.Mask" "B.Paste")
			(net "FLT_HDD25_31_N")
			(options
				(clearance outline)
				(anchor circle)
			)
			(primitives
				(gr_poly
					(pts
						(arc
							(start -0.1778 -0.5715)
							(mid -0.321484 -0.511984)
							(end -0.381 -0.3683)
						)
						(arc
							(start -0.381 0.3683)
							(mid -0.321484 0.511984)
							(end -0.1778 0.5715)
						)
						(arc
							(start 0.1778 0.5715)
							(mid 0.321484 0.511984)
							(end 0.381 0.3683)
						)
						(arc
							(start 0.381 -0.3683)
							(mid 0.321484 -0.511984)
							(end 0.1778 -0.5715)
						)
					)
					(width 0)
					(fill yes)
				)
			)
		)
		(pad "G" smd custom
			(at 0.98425 0.9525 180)
			(size 0.1905 0.1905)
			(layers "B.Cu" "B.Mask" "B.Paste")
			(net "DRIVE_A_25_31_FLT_LED")
			(options
				(clearance outline)
				(anchor circle)
			)
			(primitives
				(gr_poly
					(pts
						(arc
							(start -0.1778 -0.5715)
							(mid -0.321484 -0.511984)
							(end -0.381 -0.3683)
						)
						(arc
							(start -0.381 0.3683)
							(mid -0.321484 0.511984)
							(end -0.1778 0.5715)
						)
						(arc
							(start 0.1778 0.5715)
							(mid 0.321484 0.511984)
							(end 0.381 0.3683)
						)
						(arc
							(start 0.381 -0.3683)
							(mid 0.321484 -0.511984)
							(end 0.1778 -0.5715)
						)
					)
					(width 0)
					(fill yes)
				)
			)
		)
		(pad "S" smd custom
			(at -0.98425 0.9525 180)
			(size 0.1905 0.1905)
			(layers "B.Cu" "B.Mask" "B.Paste")
			(net "GND")
			(options
				(clearance outline)
				(anchor circle)
			)
			(primitives
				(gr_poly
					(pts
						(arc
							(start -0.1778 -0.5715)
							(mid -0.321484 -0.511984)
							(end -0.381 -0.3683)
						)
						(arc
							(start -0.381 0.3683)
							(mid -0.321484 0.511984)
							(end -0.1778 0.5715)
						)
						(arc
							(start 0.1778 0.5715)
							(mid 0.321484 0.511984)
							(end 0.381 0.3683)
						)
						(arc
							(start 0.381 -0.3683)
							(mid 0.321484 -0.511984)
							(end 0.1778 -0.5715)
						)
					)
					(width 0)
					(fill yes)
				)
			)
		)
	)
	(footprint ""
		(layer "B.Cu")
		(at 19.3548 -2.8956 -90)
		(property "Reference" "R13"
			(at 0 0 90)
			(layer "B.SilkS")
			(hide yes)
			(effects
				(font
					(size 1.27 1.27)
				)
				(justify mirror)
			)
		)
		(property "Value" "4K7R2F-GP"
			(at -0.064008 -3.993896 270)
			(unlocked yes)
			(layer "B.Fab")
			(hide yes)
			(effects
				(font
					(size 1.016 1.016)
					(thickness 0.1524)
				)
				(justify mirror)
			)
		)
		(property "Device Type" "R402H16"
			(at -0.064008 -5.517896 270)
			(unlocked yes)
			(layer "B.Fab")
			(hide yes)
			(effects
				(font
					(size 1.016 1.016)
					(thickness 0.1524)
				)
				(justify mirror)
			)
		)
		(duplicate_pad_numbers_are_jumpers no)
		(fp_line
			(start -0.508 -0.9398)
			(end 0.508 -0.9398)
			(stroke
				(width 0.1524)
				(type default)
			)
			(layer "B.SilkS")
		)
		(fp_line
			(start 0.508 -0.9398)
			(end 0.508 0.9398)
			(stroke
				(width 0.1524)
				(type default)
			)
			(layer "B.SilkS")
		)
		(fp_rect
			(start 0.508 0.9398)
			(end -0.508 -0.9398)
			(stroke
				(width 0)
				(type default)
			)
			(fill no)
			(layer "B.CrtYd")
		)
		(fp_rect
			(start 0.508 0.9398)
			(end -0.508 -0.9398)
			(stroke
				(width 0)
				(type default)
			)
			(fill no)
			(layer "B.Fab")
		)
		(pad "1" smd custom
			(at 0 -0.4445 90)
			(size 0.1397 0.1397)
			(layers "B.Cu" "B.Mask" "B.Paste")
			(net "DRIVE_A_24_30_FLT_LED")
			(options
				(clearance outline)
				(anchor circle)
			)
			(primitives
				(gr_poly
					(pts
						(arc
							(start -0.1778 0.2794)
							(mid -0.249642 0.249642)
							(end -0.2794 0.1778)
						)
						(arc
							(start -0.2794 -0.1778)
							(mid -0.249642 -0.249642)
							(end -0.1778 -0.2794)
						)
						(arc
							(start 0.1778 -0.2794)
							(mid 0.249642 -0.249642)
							(end 0.2794 -0.1778)
						)
						(arc
							(start 0.2794 0.1778)
							(mid 0.249642 0.249642)
							(end 0.1778 0.2794)
						)
					)
					(width 0)
					(fill yes)
				)
			)
		)
		(pad "2" smd custom
			(at 0 0.4445 90)
			(size 0.1397 0.1397)
			(layers "B.Cu" "B.Mask" "B.Paste")
			(net "GND")
			(options
				(clearance outline)
				(anchor circle)
			)
			(primitives
				(gr_poly
					(pts
						(arc
							(start -0.1778 0.2794)
							(mid -0.249642 0.249642)
							(end -0.2794 0.1778)
						)
						(arc
							(start -0.2794 -0.1778)
							(mid -0.249642 -0.249642)
							(end -0.1778 -0.2794)
						)
						(arc
							(start 0.1778 -0.2794)
							(mid 0.249642 -0.249642)
							(end 0.2794 -0.1778)
						)
						(arc
							(start 0.2794 0.1778)
							(mid 0.249642 0.249642)
							(end 0.1778 0.2794)
						)
					)
					(width 0)
					(fill yes)
				)
			)
		)
	)
	(footprint ""
		(layer "B.Cu")
		(at 34.417 -5.588 180)
		(property "Reference" "R4"
			(at 0 0 0)
			(layer "B.SilkS")
			(hide yes)
			(effects
				(font
					(size 1.27 1.27)
				)
				(justify mirror)
			)
		)
		(property "Value" "91R3F-1-GP"
			(at 0.0254 -2.5146 180)
			(unlocked yes)
			(layer "B.Fab")
			(hide yes)
			(effects
				(font
					(size 1.016 1.016)
					(thickness 0.1524)
				)
				(justify mirror)
			)
		)
		(property "Device Type" "R603H22"
			(at 0.0254 -4.0386 180)
			(unlocked yes)
			(layer "B.Fab")
			(hide yes)
			(effects
				(font
					(size 1.016 1.016)
					(thickness 0.1524)
				)
				(justify mirror)
			)
		)
		(duplicate_pad_numbers_are_jumpers no)
		(fp_line
			(start 0.4826 0)
			(end 0.2032 0)
			(stroke
				(width 0.2032)
				(type default)
			)
			(layer "B.SilkS")
		)
		(fp_line
			(start -0.2032 0)
			(end -0.4826 0)
			(stroke
				(width 0.2032)
				(type default)
			)
			(layer "B.SilkS")
		)
		(fp_rect
			(start 0.5842 1.3335)
			(end -0.5842 -1.3335)
			(stroke
				(width 0)
				(type default)
			)
			(fill no)
			(layer "B.CrtYd")
		)
		(fp_rect
			(start 0.5842 1.3335)
			(end -0.5842 -1.3335)
			(stroke
				(width 0)
				(type default)
			)
			(fill no)
			(layer "B.Fab")
		)
		(pad "1" smd custom
			(at 0 -0.762)
			(size 0.2159 0.2159)
			(layers "B.Cu" "B.Mask" "B.Paste")
			(net "P5V_A")
			(options
				(clearance outline)
				(anchor circle)
			)
			(primitives
				(gr_poly
					(pts
						(arc
							(start -0.3302 0.4318)
							(mid -0.402042 0.402042)
							(end -0.4318 0.3302)
						)
						(arc
							(start -0.4318 -0.3302)
							(mid -0.402042 -0.402042)
							(end -0.3302 -0.4318)
						)
						(arc
							(start 0.3302 -0.4318)
							(mid 0.402042 -0.402042)
							(end 0.4318 -0.3302)
						)
						(arc
							(start 0.4318 0.3302)
							(mid 0.402042 0.402042)
							(end 0.3302 0.4318)
						)
					)
					(width 0)
					(fill yes)
				)
			)
		)
		(pad "2" smd custom
			(at 0 0.762)
			(size 0.2159 0.2159)
			(layers "B.Cu" "B.Mask" "B.Paste")
			(net "DRV_ACT_25_31")
			(options
				(clearance outline)
				(anchor circle)
			)
			(primitives
				(gr_poly
					(pts
						(arc
							(start -0.3302 0.4318)
							(mid -0.402042 0.402042)
							(end -0.4318 0.3302)
						)
						(arc
							(start -0.4318 -0.3302)
							(mid -0.402042 -0.402042)
							(end -0.3302 -0.4318)
						)
						(arc
							(start 0.3302 -0.4318)
							(mid 0.402042 -0.402042)
							(end 0.4318 -0.3302)
						)
						(arc
							(start 0.4318 0.3302)
							(mid 0.402042 0.402042)
							(end 0.3302 0.4318)
						)
					)
					(width 0)
					(fill yes)
				)
			)
		)
	)
	(footprint ""
		(layer "B.Cu")
		(at 165.5318 -5.588)
		(property "Reference" "Q12"
			(at 0 0 0)
			(layer "B.SilkS")
			(hide yes)
			(effects
				(font
					(size 1.27 1.27)
				)
				(justify mirror)
			)
		)
		(property "Value" "SSM3K324R-GP"
			(at -0.127 -8.9662 0)
			(unlocked yes)
			(layer "B.Fab")
			(hide yes)
			(effects
				(font
					(size 1.016 1.016)
					(thickness 0.1524)
				)
				(justify mirror)
			)
		)
		(property "Device Type" "SOT23DGS2D4H35"
			(at -0.127 -10.4902 0)
			(unlocked yes)
			(layer "B.Fab")
			(hide yes)
			(effects
				(font
					(size 1.016 1.016)
					(thickness 0.1524)
				)
				(justify mirror)
			)
		)
		(duplicate_pad_numbers_are_jumpers no)
		(fp_line
			(start -1.651 -1.778)
			(end 1.651 -1.778)
			(stroke
				(width 0.1524)
				(type default)
			)
			(layer "B.SilkS")
		)
		(fp_line
			(start -1.651 1.778)
			(end -1.651 -1.778)
			(stroke
				(width 0.1524)
				(type default)
			)
			(layer "B.SilkS")
		)
		(fp_line
			(start 1.651 -1.778)
			(end 1.651 1.778)
			(stroke
				(width 0.1524)
				(type default)
			)
			(layer "B.SilkS")
		)
		(fp_line
			(start 1.651 1.778)
			(end -1.651 1.778)
			(stroke
				(width 0.1524)
				(type default)
			)
			(layer "B.SilkS")
		)
		(fp_poly
			(pts
				(xy 1.778 1.8796) (xy 1.778 -1.8796) (xy -1.778 -1.8796) (xy -1.778 1.8796)
			)
			(stroke
				(width 0)
				(type default)
			)
			(fill no)
			(layer "B.CrtYd")
		)
		(fp_poly
			(pts
				(xy 1.778 1.8796) (xy 1.778 -1.8796) (xy -1.778 -1.8796) (xy -1.778 1.8796)
			)
			(stroke
				(width 0)
				(type default)
			)
			(fill no)
			(layer "B.Fab")
		)
		(pad "D" smd custom
			(at 0 -0.9525 180)
			(size 0.1905 0.1905)
			(layers "B.Cu" "B.Mask" "B.Paste")
			(net "DRV_ACT_29_35_N")
			(options
				(clearance outline)
				(anchor circle)
			)
			(primitives
				(gr_poly
					(pts
						(arc
							(start -0.1778 -0.5715)
							(mid -0.321484 -0.511984)
							(end -0.381 -0.3683)
						)
						(arc
							(start -0.381 0.3683)
							(mid -0.321484 0.511984)
							(end -0.1778 0.5715)
						)
						(arc
							(start 0.1778 0.5715)
							(mid 0.321484 0.511984)
							(end 0.381 0.3683)
						)
						(arc
							(start 0.381 -0.3683)
							(mid 0.321484 -0.511984)
							(end 0.1778 -0.5715)
						)
					)
					(width 0)
					(fill yes)
				)
			)
		)
		(pad "G" smd custom
			(at 0.98425 0.9525 180)
			(size 0.1905 0.1905)
			(layers "B.Cu" "B.Mask" "B.Paste")
			(net "DRIVE_A_29_35_ACT")
			(options
				(clearance outline)
				(anchor circle)
			)
			(primitives
				(gr_poly
					(pts
						(arc
							(start -0.1778 -0.5715)
							(mid -0.321484 -0.511984)
							(end -0.381 -0.3683)
						)
						(arc
							(start -0.381 0.3683)
							(mid -0.321484 0.511984)
							(end -0.1778 0.5715)
						)
						(arc
							(start 0.1778 0.5715)
							(mid 0.321484 0.511984)
							(end 0.381 0.3683)
						)
						(arc
							(start 0.381 -0.3683)
							(mid 0.321484 -0.511984)
							(end 0.1778 -0.5715)
						)
					)
					(width 0)
					(fill yes)
				)
			)
		)
		(pad "S" smd custom
			(at -0.98425 0.9525 180)
			(size 0.1905 0.1905)
			(layers "B.Cu" "B.Mask" "B.Paste")
			(net "GND")
			(options
				(clearance outline)
				(anchor circle)
			)
			(primitives
				(gr_poly
					(pts
						(arc
							(start -0.1778 -0.5715)
							(mid -0.321484 -0.511984)
							(end -0.381 -0.3683)
						)
						(arc
							(start -0.381 0.3683)
							(mid -0.321484 0.511984)
							(end -0.1778 0.5715)
						)
						(arc
							(start 0.1778 0.5715)
							(mid 0.321484 0.511984)
							(end 0.381 0.3683)
						)
						(arc
							(start 0.381 -0.3683)
							(mid 0.321484 -0.511984)
							(end 0.1778 -0.5715)
						)
					)
					(width 0)
					(fill yes)
				)
			)
		)
	)
	(footprint ""
		(layer "B.Cu")
		(at 106.4006 -5.9182)
		(property "Reference" "Q7"
			(at 0 0 0)
			(layer "B.SilkS")
			(hide yes)
			(effects
				(font
					(size 1.27 1.27)
				)
				(justify mirror)
			)
		)
		(property "Value" "2N7002K-2-GP"
			(at -0.127 -8.9662 0)
			(unlocked yes)
			(layer "B.Fab")
			(hide yes)
			(effects
				(font
					(size 1.016 1.016)
					(thickness 0.1524)
				)
				(justify mirror)
			)
		)
		(property "Device Type" "SOT23DGS2D4H44"
			(at -0.127 -10.4902 0)
			(unlocked yes)
			(layer "B.Fab")
			(hide yes)
			(effects
				(font
					(size 1.016 1.016)
					(thickness 0.1524)
				)
				(justify mirror)
			)
		)
		(duplicate_pad_numbers_are_jumpers no)
		(fp_line
			(start -1.651 -1.778)
			(end 1.651 -1.778)
			(stroke
				(width 0.1524)
				(type default)
			)
			(layer "B.SilkS")
		)
		(fp_line
			(start -1.651 1.778)
			(end -1.651 -1.778)
			(stroke
				(width 0.1524)
				(type default)
			)
			(layer "B.SilkS")
		)
		(fp_line
			(start 1.651 -1.778)
			(end 1.651 1.778)
			(stroke
				(width 0.1524)
				(type default)
			)
			(layer "B.SilkS")
		)
		(fp_line
			(start 1.651 1.778)
			(end -1.651 1.778)
			(stroke
				(width 0.1524)
				(type default)
			)
			(layer "B.SilkS")
		)
		(fp_poly
			(pts
				(xy 1.778 1.8796) (xy 1.778 -1.8796) (xy -1.778 -1.8796) (xy -1.778 1.8796)
			)
			(stroke
				(width 0)
				(type default)
			)
			(fill no)
			(layer "B.CrtYd")
		)
		(fp_poly
			(pts
				(xy 1.778 1.8796) (xy 1.778 -1.8796) (xy -1.778 -1.8796) (xy -1.778 1.8796)
			)
			(stroke
				(width 0)
				(type default)
			)
			(fill no)
			(layer "B.Fab")
		)
		(pad "D" smd custom
			(at 0 -0.9525 180)
			(size 0.1905 0.1905)
			(layers "B.Cu" "B.Mask" "B.Paste")
			(net "FLT_HDD27_33_N")
			(options
				(clearance outline)
				(anchor circle)
			)
			(primitives
				(gr_poly
					(pts
						(arc
							(start -0.1778 -0.5715)
							(mid -0.321484 -0.511984)
							(end -0.381 -0.3683)
						)
						(arc
							(start -0.381 0.3683)
							(mid -0.321484 0.511984)
							(end -0.1778 0.5715)
						)
						(arc
							(start 0.1778 0.5715)
							(mid 0.321484 0.511984)
							(end 0.381 0.3683)
						)
						(arc
							(start 0.381 -0.3683)
							(mid 0.321484 -0.511984)
							(end 0.1778 -0.5715)
						)
					)
					(width 0)
					(fill yes)
				)
			)
		)
		(pad "G" smd custom
			(at 0.98425 0.9525 180)
			(size 0.1905 0.1905)
			(layers "B.Cu" "B.Mask" "B.Paste")
			(net "DRIVE_A_27_33_FLT_LED")
			(options
				(clearance outline)
				(anchor circle)
			)
			(primitives
				(gr_poly
					(pts
						(arc
							(start -0.1778 -0.5715)
							(mid -0.321484 -0.511984)
							(end -0.381 -0.3683)
						)
						(arc
							(start -0.381 0.3683)
							(mid -0.321484 0.511984)
							(end -0.1778 0.5715)
						)
						(arc
							(start 0.1778 0.5715)
							(mid 0.321484 0.511984)
							(end 0.381 0.3683)
						)
						(arc
							(start 0.381 -0.3683)
							(mid 0.321484 -0.511984)
							(end 0.1778 -0.5715)
						)
					)
					(width 0)
					(fill yes)
				)
			)
		)
		(pad "S" smd custom
			(at -0.98425 0.9525 180)
			(size 0.1905 0.1905)
			(layers "B.Cu" "B.Mask" "B.Paste")
			(net "GND")
			(options
				(clearance outline)
				(anchor circle)
			)
			(primitives
				(gr_poly
					(pts
						(arc
							(start -0.1778 -0.5715)
							(mid -0.321484 -0.511984)
							(end -0.381 -0.3683)
						)
						(arc
							(start -0.381 0.3683)
							(mid -0.321484 0.511984)
							(end -0.1778 0.5715)
						)
						(arc
							(start 0.1778 0.5715)
							(mid 0.321484 0.511984)
							(end 0.381 0.3683)
						)
						(arc
							(start 0.381 -0.3683)
							(mid 0.321484 -0.511984)
							(end 0.1778 -0.5715)
						)
					)
					(width 0)
					(fill yes)
				)
			)
		)
	)
	(footprint ""
		(layer "B.Cu")
		(at 16.3322 -5.8166 180)
		(property "Reference" "R1"
			(at 0 0 0)
			(layer "B.SilkS")
			(hide yes)
			(effects
				(font
					(size 1.27 1.27)
				)
				(justify mirror)
			)
		)
		(property "Value" "130R3F-GP"
			(at 0.0254 -2.5146 180)
			(unlocked yes)
			(layer "B.Fab")
			(hide yes)
			(effects
				(font
					(size 1.016 1.016)
					(thickness 0.1524)
				)
				(justify mirror)
			)
		)
		(property "Device Type" "R603H22"
			(at 0.0254 -4.0386 180)
			(unlocked yes)
			(layer "B.Fab")
			(hide yes)
			(effects
				(font
					(size 1.016 1.016)
					(thickness 0.1524)
				)
				(justify mirror)
			)
		)
		(duplicate_pad_numbers_are_jumpers no)
		(fp_line
			(start 0.4826 0)
			(end 0.2032 0)
			(stroke
				(width 0.2032)
				(type default)
			)
			(layer "B.SilkS")
		)
		(fp_line
			(start -0.2032 0)
			(end -0.4826 0)
			(stroke
				(width 0.2032)
				(type default)
			)
			(layer "B.SilkS")
		)
		(fp_rect
			(start 0.5842 1.3335)
			(end -0.5842 -1.3335)
			(stroke
				(width 0)
				(type default)
			)
			(fill no)
			(layer "B.CrtYd")
		)
		(fp_rect
			(start 0.5842 1.3335)
			(end -0.5842 -1.3335)
			(stroke
				(width 0)
				(type default)
			)
			(fill no)
			(layer "B.Fab")
		)
		(pad "1" smd custom
			(at 0 -0.762)
			(size 0.2159 0.2159)
			(layers "B.Cu" "B.Mask" "B.Paste")
			(net "P5V_A")
			(options
				(clearance outline)
				(anchor circle)
			)
			(primitives
				(gr_poly
					(pts
						(arc
							(start -0.3302 0.4318)
							(mid -0.402042 0.402042)
							(end -0.4318 0.3302)
						)
						(arc
							(start -0.4318 -0.3302)
							(mid -0.402042 -0.402042)
							(end -0.3302 -0.4318)
						)
						(arc
							(start 0.3302 -0.4318)
							(mid 0.402042 -0.402042)
							(end 0.4318 -0.3302)
						)
						(arc
							(start 0.4318 0.3302)
							(mid 0.402042 0.402042)
							(end 0.3302 0.4318)
						)
					)
					(width 0)
					(fill yes)
				)
			)
		)
		(pad "2" smd custom
			(at 0 0.762)
			(size 0.2159 0.2159)
			(layers "B.Cu" "B.Mask" "B.Paste")
			(net "FLT_HDD24_30")
			(options
				(clearance outline)
				(anchor circle)
			)
			(primitives
				(gr_poly
					(pts
						(arc
							(start -0.3302 0.4318)
							(mid -0.402042 0.402042)
							(end -0.4318 0.3302)
						)
						(arc
							(start -0.4318 -0.3302)
							(mid -0.402042 -0.402042)
							(end -0.3302 -0.4318)
						)
						(arc
							(start 0.3302 -0.4318)
							(mid 0.402042 -0.402042)
							(end 0.4318 -0.3302)
						)
						(arc
							(start 0.4318 0.3302)
							(mid 0.402042 0.402042)
							(end 0.3302 0.4318)
						)
					)
					(width 0)
					(fill yes)
				)
			)
		)
	)
	(footprint ""
		(layer "B.Cu")
		(at 70.757796 -6.06298 180)
		(property "Reference" "R6"
			(at 0 0 0)
			(layer "B.SilkS")
			(hide yes)
			(effects
				(font
					(size 1.27 1.27)
				)
				(justify mirror)
			)
		)
		(property "Value" "91R3F-1-GP"
			(at 0.0254 -2.5146 180)
			(unlocked yes)
			(layer "B.Fab")
			(hide yes)
			(effects
				(font
					(size 1.016 1.016)
					(thickness 0.1524)
				)
				(justify mirror)
			)
		)
		(property "Device Type" "R603H22"
			(at 0.0254 -4.0386 180)
			(unlocked yes)
			(layer "B.Fab")
			(hide yes)
			(effects
				(font
					(size 1.016 1.016)
					(thickness 0.1524)
				)
				(justify mirror)
			)
		)
		(duplicate_pad_numbers_are_jumpers no)
		(fp_line
			(start 0.4826 0)
			(end 0.2032 0)
			(stroke
				(width 0.2032)
				(type default)
			)
			(layer "B.SilkS")
		)
		(fp_line
			(start -0.2032 0)
			(end -0.4826 0)
			(stroke
				(width 0.2032)
				(type default)
			)
			(layer "B.SilkS")
		)
		(fp_rect
			(start 0.5842 1.3335)
			(end -0.5842 -1.3335)
			(stroke
				(width 0)
				(type default)
			)
			(fill no)
			(layer "B.CrtYd")
		)
		(fp_rect
			(start 0.5842 1.3335)
			(end -0.5842 -1.3335)
			(stroke
				(width 0)
				(type default)
			)
			(fill no)
			(layer "B.Fab")
		)
		(pad "1" smd custom
			(at 0 -0.762)
			(size 0.2159 0.2159)
			(layers "B.Cu" "B.Mask" "B.Paste")
			(net "P5V_A")
			(options
				(clearance outline)
				(anchor circle)
			)
			(primitives
				(gr_poly
					(pts
						(arc
							(start -0.3302 0.4318)
							(mid -0.402042 0.402042)
							(end -0.4318 0.3302)
						)
						(arc
							(start -0.4318 -0.3302)
							(mid -0.402042 -0.402042)
							(end -0.3302 -0.4318)
						)
						(arc
							(start 0.3302 -0.4318)
							(mid 0.402042 -0.402042)
							(end 0.4318 -0.3302)
						)
						(arc
							(start 0.4318 0.3302)
							(mid 0.402042 0.402042)
							(end 0.3302 0.4318)
						)
					)
					(width 0)
					(fill yes)
				)
			)
		)
		(pad "2" smd custom
			(at 0 0.762)
			(size 0.2159 0.2159)
			(layers "B.Cu" "B.Mask" "B.Paste")
			(net "DRV_ACT_26_32")
			(options
				(clearance outline)
				(anchor circle)
			)
			(primitives
				(gr_poly
					(pts
						(arc
							(start -0.3302 0.4318)
							(mid -0.402042 0.402042)
							(end -0.4318 0.3302)
						)
						(arc
							(start -0.4318 -0.3302)
							(mid -0.402042 -0.402042)
							(end -0.3302 -0.4318)
						)
						(arc
							(start 0.3302 -0.4318)
							(mid 0.402042 -0.402042)
							(end 0.4318 -0.3302)
						)
						(arc
							(start 0.4318 0.3302)
							(mid 0.402042 0.402042)
							(end 0.3302 0.4318)
						)
					)
					(width 0)
					(fill yes)
				)
			)
		)
	)
	(footprint ""
		(layer "B.Cu")
		(at 142.24 -3.302 -90)
		(property "Reference" "R22"
			(at 0 0 90)
			(layer "B.SilkS")
			(hide yes)
			(effects
				(font
					(size 1.27 1.27)
				)
				(justify mirror)
			)
		)
		(property "Value" "4K7R2F-GP"
			(at -0.064008 -3.993896 270)
			(unlocked yes)
			(layer "B.Fab")
			(hide yes)
			(effects
				(font
					(size 1.016 1.016)
					(thickness 0.1524)
				)
				(justify mirror)
			)
		)
		(property "Device Type" "R402H16"
			(at -0.064008 -5.517896 270)
			(unlocked yes)
			(layer "B.Fab")
			(hide yes)
			(effects
				(font
					(size 1.016 1.016)
					(thickness 0.1524)
				)
				(justify mirror)
			)
		)
		(duplicate_pad_numbers_are_jumpers no)
		(fp_line
			(start -0.508 -0.9398)
			(end 0.508 -0.9398)
			(stroke
				(width 0.1524)
				(type default)
			)
			(layer "B.SilkS")
		)
		(fp_line
			(start 0.508 -0.9398)
			(end 0.508 0.9398)
			(stroke
				(width 0.1524)
				(type default)
			)
			(layer "B.SilkS")
		)
		(fp_rect
			(start 0.508 0.9398)
			(end -0.508 -0.9398)
			(stroke
				(width 0)
				(type default)
			)
			(fill no)
			(layer "B.CrtYd")
		)
		(fp_rect
			(start 0.508 0.9398)
			(end -0.508 -0.9398)
			(stroke
				(width 0)
				(type default)
			)
			(fill no)
			(layer "B.Fab")
		)
		(pad "1" smd custom
			(at 0 -0.4445 90)
			(size 0.1397 0.1397)
			(layers "B.Cu" "B.Mask" "B.Paste")
			(net "DRIVE_A_28_34_ACT")
			(options
				(clearance outline)
				(anchor circle)
			)
			(primitives
				(gr_poly
					(pts
						(arc
							(start -0.1778 0.2794)
							(mid -0.249642 0.249642)
							(end -0.2794 0.1778)
						)
						(arc
							(start -0.2794 -0.1778)
							(mid -0.249642 -0.249642)
							(end -0.1778 -0.2794)
						)
						(arc
							(start 0.1778 -0.2794)
							(mid 0.249642 -0.249642)
							(end 0.2794 -0.1778)
						)
						(arc
							(start 0.2794 0.1778)
							(mid 0.249642 0.249642)
							(end 0.1778 0.2794)
						)
					)
					(width 0)
					(fill yes)
				)
			)
		)
		(pad "2" smd custom
			(at 0 0.4445 90)
			(size 0.1397 0.1397)
			(layers "B.Cu" "B.Mask" "B.Paste")
			(net "GND")
			(options
				(clearance outline)
				(anchor circle)
			)
			(primitives
				(gr_poly
					(pts
						(arc
							(start -0.1778 0.2794)
							(mid -0.249642 0.249642)
							(end -0.2794 0.1778)
						)
						(arc
							(start -0.2794 -0.1778)
							(mid -0.249642 -0.249642)
							(end -0.1778 -0.2794)
						)
						(arc
							(start 0.1778 -0.2794)
							(mid 0.249642 -0.249642)
							(end 0.2794 -0.1778)
						)
						(arc
							(start 0.2794 0.1778)
							(mid 0.249642 0.249642)
							(end 0.1778 0.2794)
						)
					)
					(width 0)
					(fill yes)
				)
			)
		)
	)
	(footprint ""
		(layer "B.Cu")
		(at 18.7198 -5.4102)
		(property "Reference" "Q1"
			(at 0 0 0)
			(layer "B.SilkS")
			(hide yes)
			(effects
				(font
					(size 1.27 1.27)
				)
				(justify mirror)
			)
		)
		(property "Value" "2N7002K-2-GP"
			(at -0.127 -8.9662 0)
			(unlocked yes)
			(layer "B.Fab")
			(hide yes)
			(effects
				(font
					(size 1.016 1.016)
					(thickness 0.1524)
				)
				(justify mirror)
			)
		)
		(property "Device Type" "SOT23DGS2D4H44"
			(at -0.127 -10.4902 0)
			(unlocked yes)
			(layer "B.Fab")
			(hide yes)
			(effects
				(font
					(size 1.016 1.016)
					(thickness 0.1524)
				)
				(justify mirror)
			)
		)
		(duplicate_pad_numbers_are_jumpers no)
		(fp_line
			(start -1.651 -1.778)
			(end 1.651 -1.778)
			(stroke
				(width 0.1524)
				(type default)
			)
			(layer "B.SilkS")
		)
		(fp_line
			(start -1.651 1.778)
			(end -1.651 -1.778)
			(stroke
				(width 0.1524)
				(type default)
			)
			(layer "B.SilkS")
		)
		(fp_line
			(start 1.651 -1.778)
			(end 1.651 1.778)
			(stroke
				(width 0.1524)
				(type default)
			)
			(layer "B.SilkS")
		)
		(fp_line
			(start 1.651 1.778)
			(end -1.651 1.778)
			(stroke
				(width 0.1524)
				(type default)
			)
			(layer "B.SilkS")
		)
		(fp_poly
			(pts
				(xy 1.778 1.8796) (xy 1.778 -1.8796) (xy -1.778 -1.8796) (xy -1.778 1.8796)
			)
			(stroke
				(width 0)
				(type default)
			)
			(fill no)
			(layer "B.CrtYd")
		)
		(fp_poly
			(pts
				(xy 1.778 1.8796) (xy 1.778 -1.8796) (xy -1.778 -1.8796) (xy -1.778 1.8796)
			)
			(stroke
				(width 0)
				(type default)
			)
			(fill no)
			(layer "B.Fab")
		)
		(pad "D" smd custom
			(at 0 -0.9525 180)
			(size 0.1905 0.1905)
			(layers "B.Cu" "B.Mask" "B.Paste")
			(net "FLT_HDD24_30_N")
			(options
				(clearance outline)
				(anchor circle)
			)
			(primitives
				(gr_poly
					(pts
						(arc
							(start -0.1778 -0.5715)
							(mid -0.321484 -0.511984)
							(end -0.381 -0.3683)
						)
						(arc
							(start -0.381 0.3683)
							(mid -0.321484 0.511984)
							(end -0.1778 0.5715)
						)
						(arc
							(start 0.1778 0.5715)
							(mid 0.321484 0.511984)
							(end 0.381 0.3683)
						)
						(arc
							(start 0.381 -0.3683)
							(mid 0.321484 -0.511984)
							(end 0.1778 -0.5715)
						)
					)
					(width 0)
					(fill yes)
				)
			)
		)
		(pad "G" smd custom
			(at 0.98425 0.9525 180)
			(size 0.1905 0.1905)
			(layers "B.Cu" "B.Mask" "B.Paste")
			(net "DRIVE_A_24_30_FLT_LED")
			(options
				(clearance outline)
				(anchor circle)
			)
			(primitives
				(gr_poly
					(pts
						(arc
							(start -0.1778 -0.5715)
							(mid -0.321484 -0.511984)
							(end -0.381 -0.3683)
						)
						(arc
							(start -0.381 0.3683)
							(mid -0.321484 0.511984)
							(end -0.1778 0.5715)
						)
						(arc
							(start 0.1778 0.5715)
							(mid 0.321484 0.511984)
							(end 0.381 0.3683)
						)
						(arc
							(start 0.381 -0.3683)
							(mid 0.321484 -0.511984)
							(end 0.1778 -0.5715)
						)
					)
					(width 0)
					(fill yes)
				)
			)
		)
		(pad "S" smd custom
			(at -0.98425 0.9525 180)
			(size 0.1905 0.1905)
			(layers "B.Cu" "B.Mask" "B.Paste")
			(net "GND")
			(options
				(clearance outline)
				(anchor circle)
			)
			(primitives
				(gr_poly
					(pts
						(arc
							(start -0.1778 -0.5715)
							(mid -0.321484 -0.511984)
							(end -0.381 -0.3683)
						)
						(arc
							(start -0.381 0.3683)
							(mid -0.321484 0.511984)
							(end -0.1778 0.5715)
						)
						(arc
							(start 0.1778 0.5715)
							(mid 0.321484 0.511984)
							(end 0.381 0.3683)
						)
						(arc
							(start 0.381 -0.3683)
							(mid 0.321484 -0.511984)
							(end 0.1778 -0.5715)
						)
					)
					(width 0)
					(fill yes)
				)
			)
		)
	)
	(footprint ""
		(layer "B.Cu")
		(at 26.0604 -5.9436 180)
		(property "Reference" "R3"
			(at 0 0 0)
			(layer "B.SilkS")
			(hide yes)
			(effects
				(font
					(size 1.27 1.27)
				)
				(justify mirror)
			)
		)
		(property "Value" "130R3F-GP"
			(at 0.0254 -2.5146 180)
			(unlocked yes)
			(layer "B.Fab")
			(hide yes)
			(effects
				(font
					(size 1.016 1.016)
					(thickness 0.1524)
				)
				(justify mirror)
			)
		)
		(property "Device Type" "R603H22"
			(at 0.0254 -4.0386 180)
			(unlocked yes)
			(layer "B.Fab")
			(hide yes)
			(effects
				(font
					(size 1.016 1.016)
					(thickness 0.1524)
				)
				(justify mirror)
			)
		)
		(duplicate_pad_numbers_are_jumpers no)
		(fp_line
			(start 0.4826 0)
			(end 0.2032 0)
			(stroke
				(width 0.2032)
				(type default)
			)
			(layer "B.SilkS")
		)
		(fp_line
			(start -0.2032 0)
			(end -0.4826 0)
			(stroke
				(width 0.2032)
				(type default)
			)
			(layer "B.SilkS")
		)
		(fp_rect
			(start 0.5842 1.3335)
			(end -0.5842 -1.3335)
			(stroke
				(width 0)
				(type default)
			)
			(fill no)
			(layer "B.CrtYd")
		)
		(fp_rect
			(start 0.5842 1.3335)
			(end -0.5842 -1.3335)
			(stroke
				(width 0)
				(type default)
			)
			(fill no)
			(layer "B.Fab")
		)
		(pad "1" smd custom
			(at 0 -0.762)
			(size 0.2159 0.2159)
			(layers "B.Cu" "B.Mask" "B.Paste")
			(net "P5V_A")
			(options
				(clearance outline)
				(anchor circle)
			)
			(primitives
				(gr_poly
					(pts
						(arc
							(start -0.3302 0.4318)
							(mid -0.402042 0.402042)
							(end -0.4318 0.3302)
						)
						(arc
							(start -0.4318 -0.3302)
							(mid -0.402042 -0.402042)
							(end -0.3302 -0.4318)
						)
						(arc
							(start 0.3302 -0.4318)
							(mid 0.402042 -0.402042)
							(end 0.4318 -0.3302)
						)
						(arc
							(start 0.4318 0.3302)
							(mid 0.402042 0.402042)
							(end 0.3302 0.4318)
						)
					)
					(width 0)
					(fill yes)
				)
			)
		)
		(pad "2" smd custom
			(at 0 0.762)
			(size 0.2159 0.2159)
			(layers "B.Cu" "B.Mask" "B.Paste")
			(net "FLT_HDD25_31")
			(options
				(clearance outline)
				(anchor circle)
			)
			(primitives
				(gr_poly
					(pts
						(arc
							(start -0.3302 0.4318)
							(mid -0.402042 0.402042)
							(end -0.4318 0.3302)
						)
						(arc
							(start -0.4318 -0.3302)
							(mid -0.402042 -0.402042)
							(end -0.3302 -0.4318)
						)
						(arc
							(start 0.3302 -0.4318)
							(mid 0.402042 -0.402042)
							(end 0.4318 -0.3302)
						)
						(arc
							(start 0.4318 0.3302)
							(mid 0.402042 0.402042)
							(end 0.3302 0.4318)
						)
					)
					(width 0)
					(fill yes)
				)
			)
		)
	)
	(footprint ""
		(layer "B.Cu")
		(at 144.4752 -5.8928 180)
		(property "Reference" "R10"
			(at 0 0 0)
			(layer "B.SilkS")
			(hide yes)
			(effects
				(font
					(size 1.27 1.27)
				)
				(justify mirror)
			)
		)
		(property "Value" "91R3F-1-GP"
			(at 0.0254 -2.5146 180)
			(unlocked yes)
			(layer "B.Fab")
			(hide yes)
			(effects
				(font
					(size 1.016 1.016)
					(thickness 0.1524)
				)
				(justify mirror)
			)
		)
		(property "Device Type" "R603H22"
			(at 0.0254 -4.0386 180)
			(unlocked yes)
			(layer "B.Fab")
			(hide yes)
			(effects
				(font
					(size 1.016 1.016)
					(thickness 0.1524)
				)
				(justify mirror)
			)
		)
		(duplicate_pad_numbers_are_jumpers no)
		(fp_line
			(start 0.4826 0)
			(end 0.2032 0)
			(stroke
				(width 0.2032)
				(type default)
			)
			(layer "B.SilkS")
		)
		(fp_line
			(start -0.2032 0)
			(end -0.4826 0)
			(stroke
				(width 0.2032)
				(type default)
			)
			(layer "B.SilkS")
		)
		(fp_rect
			(start 0.5842 1.3335)
			(end -0.5842 -1.3335)
			(stroke
				(width 0)
				(type default)
			)
			(fill no)
			(layer "B.CrtYd")
		)
		(fp_rect
			(start 0.5842 1.3335)
			(end -0.5842 -1.3335)
			(stroke
				(width 0)
				(type default)
			)
			(fill no)
			(layer "B.Fab")
		)
		(pad "1" smd custom
			(at 0 -0.762)
			(size 0.2159 0.2159)
			(layers "B.Cu" "B.Mask" "B.Paste")
			(net "P5V_A")
			(options
				(clearance outline)
				(anchor circle)
			)
			(primitives
				(gr_poly
					(pts
						(arc
							(start -0.3302 0.4318)
							(mid -0.402042 0.402042)
							(end -0.4318 0.3302)
						)
						(arc
							(start -0.4318 -0.3302)
							(mid -0.402042 -0.402042)
							(end -0.3302 -0.4318)
						)
						(arc
							(start 0.3302 -0.4318)
							(mid 0.402042 -0.402042)
							(end 0.4318 -0.3302)
						)
						(arc
							(start 0.4318 0.3302)
							(mid 0.402042 0.402042)
							(end 0.3302 0.4318)
						)
					)
					(width 0)
					(fill yes)
				)
			)
		)
		(pad "2" smd custom
			(at 0 0.762)
			(size 0.2159 0.2159)
			(layers "B.Cu" "B.Mask" "B.Paste")
			(net "DRV_ACT_28_34")
			(options
				(clearance outline)
				(anchor circle)
			)
			(primitives
				(gr_poly
					(pts
						(arc
							(start -0.3302 0.4318)
							(mid -0.402042 0.402042)
							(end -0.4318 0.3302)
						)
						(arc
							(start -0.4318 -0.3302)
							(mid -0.402042 -0.402042)
							(end -0.3302 -0.4318)
						)
						(arc
							(start 0.3302 -0.4318)
							(mid 0.402042 -0.402042)
							(end 0.4318 -0.3302)
						)
						(arc
							(start 0.4318 0.3302)
							(mid 0.402042 0.402042)
							(end 0.3302 0.4318)
						)
					)
					(width 0)
					(fill yes)
				)
			)
		)
	)
	(footprint ""
		(layer "B.Cu")
		(at 68.378578 -5.652516)
		(property "Reference" "Q5"
			(at 0 0 0)
			(layer "B.SilkS")
			(hide yes)
			(effects
				(font
					(size 1.27 1.27)
				)
				(justify mirror)
			)
		)
		(property "Value" "2N7002K-2-GP"
			(at -0.127 -8.9662 0)
			(unlocked yes)
			(layer "B.Fab")
			(hide yes)
			(effects
				(font
					(size 1.016 1.016)
					(thickness 0.1524)
				)
				(justify mirror)
			)
		)
		(property "Device Type" "SOT23DGS2D4H44"
			(at -0.127 -10.4902 0)
			(unlocked yes)
			(layer "B.Fab")
			(hide yes)
			(effects
				(font
					(size 1.016 1.016)
					(thickness 0.1524)
				)
				(justify mirror)
			)
		)
		(duplicate_pad_numbers_are_jumpers no)
		(fp_line
			(start -1.651 -1.778)
			(end 1.651 -1.778)
			(stroke
				(width 0.1524)
				(type default)
			)
			(layer "B.SilkS")
		)
		(fp_line
			(start -1.651 1.778)
			(end -1.651 -1.778)
			(stroke
				(width 0.1524)
				(type default)
			)
			(layer "B.SilkS")
		)
		(fp_line
			(start 1.651 -1.778)
			(end 1.651 1.778)
			(stroke
				(width 0.1524)
				(type default)
			)
			(layer "B.SilkS")
		)
		(fp_line
			(start 1.651 1.778)
			(end -1.651 1.778)
			(stroke
				(width 0.1524)
				(type default)
			)
			(layer "B.SilkS")
		)
		(fp_poly
			(pts
				(xy 1.778 1.8796) (xy 1.778 -1.8796) (xy -1.778 -1.8796) (xy -1.778 1.8796)
			)
			(stroke
				(width 0)
				(type default)
			)
			(fill no)
			(layer "B.CrtYd")
		)
		(fp_poly
			(pts
				(xy 1.778 1.8796) (xy 1.778 -1.8796) (xy -1.778 -1.8796) (xy -1.778 1.8796)
			)
			(stroke
				(width 0)
				(type default)
			)
			(fill no)
			(layer "B.Fab")
		)
		(pad "D" smd custom
			(at 0 -0.9525 180)
			(size 0.1905 0.1905)
			(layers "B.Cu" "B.Mask" "B.Paste")
			(net "FLT_HDD26_32_N")
			(options
				(clearance outline)
				(anchor circle)
			)
			(primitives
				(gr_poly
					(pts
						(arc
							(start -0.1778 -0.5715)
							(mid -0.321484 -0.511984)
							(end -0.381 -0.3683)
						)
						(arc
							(start -0.381 0.3683)
							(mid -0.321484 0.511984)
							(end -0.1778 0.5715)
						)
						(arc
							(start 0.1778 0.5715)
							(mid 0.321484 0.511984)
							(end 0.381 0.3683)
						)
						(arc
							(start 0.381 -0.3683)
							(mid 0.321484 -0.511984)
							(end 0.1778 -0.5715)
						)
					)
					(width 0)
					(fill yes)
				)
			)
		)
		(pad "G" smd custom
			(at 0.98425 0.9525 180)
			(size 0.1905 0.1905)
			(layers "B.Cu" "B.Mask" "B.Paste")
			(net "DRIVE_A_26_32_FLT_LED")
			(options
				(clearance outline)
				(anchor circle)
			)
			(primitives
				(gr_poly
					(pts
						(arc
							(start -0.1778 -0.5715)
							(mid -0.321484 -0.511984)
							(end -0.381 -0.3683)
						)
						(arc
							(start -0.381 0.3683)
							(mid -0.321484 0.511984)
							(end -0.1778 0.5715)
						)
						(arc
							(start 0.1778 0.5715)
							(mid 0.321484 0.511984)
							(end 0.381 0.3683)
						)
						(arc
							(start 0.381 -0.3683)
							(mid 0.321484 -0.511984)
							(end 0.1778 -0.5715)
						)
					)
					(width 0)
					(fill yes)
				)
			)
		)
		(pad "S" smd custom
			(at -0.98425 0.9525 180)
			(size 0.1905 0.1905)
			(layers "B.Cu" "B.Mask" "B.Paste")
			(net "GND")
			(options
				(clearance outline)
				(anchor circle)
			)
			(primitives
				(gr_poly
					(pts
						(arc
							(start -0.1778 -0.5715)
							(mid -0.321484 -0.511984)
							(end -0.381 -0.3683)
						)
						(arc
							(start -0.381 0.3683)
							(mid -0.321484 0.511984)
							(end -0.1778 0.5715)
						)
						(arc
							(start 0.1778 0.5715)
							(mid 0.321484 0.511984)
							(end 0.381 0.3683)
						)
						(arc
							(start 0.381 -0.3683)
							(mid 0.321484 -0.511984)
							(end 0.1778 -0.5715)
						)
					)
					(width 0)
					(fill yes)
				)
			)
		)
	)
	(footprint ""
		(layer "B.Cu")
		(at 110.2106 -3.5052 -90)
		(property "Reference" "R20"
			(at 0 0 90)
			(layer "B.SilkS")
			(hide yes)
			(effects
				(font
					(size 1.27 1.27)
				)
				(justify mirror)
			)
		)
		(property "Value" "4K7R2F-GP"
			(at -0.064008 -3.993896 270)
			(unlocked yes)
			(layer "B.Fab")
			(hide yes)
			(effects
				(font
					(size 1.016 1.016)
					(thickness 0.1524)
				)
				(justify mirror)
			)
		)
		(property "Device Type" "R402H16"
			(at -0.064008 -5.517896 270)
			(unlocked yes)
			(layer "B.Fab")
			(hide yes)
			(effects
				(font
					(size 1.016 1.016)
					(thickness 0.1524)
				)
				(justify mirror)
			)
		)
		(duplicate_pad_numbers_are_jumpers no)
		(fp_line
			(start -0.508 -0.9398)
			(end 0.508 -0.9398)
			(stroke
				(width 0.1524)
				(type default)
			)
			(layer "B.SilkS")
		)
		(fp_line
			(start 0.508 -0.9398)
			(end 0.508 0.9398)
			(stroke
				(width 0.1524)
				(type default)
			)
			(layer "B.SilkS")
		)
		(fp_rect
			(start 0.508 0.9398)
			(end -0.508 -0.9398)
			(stroke
				(width 0)
				(type default)
			)
			(fill no)
			(layer "B.CrtYd")
		)
		(fp_rect
			(start 0.508 0.9398)
			(end -0.508 -0.9398)
			(stroke
				(width 0)
				(type default)
			)
			(fill no)
			(layer "B.Fab")
		)
		(pad "1" smd custom
			(at 0 -0.4445 90)
			(size 0.1397 0.1397)
			(layers "B.Cu" "B.Mask" "B.Paste")
			(net "DRIVE_A_27_33_ACT")
			(options
				(clearance outline)
				(anchor circle)
			)
			(primitives
				(gr_poly
					(pts
						(arc
							(start -0.1778 0.2794)
							(mid -0.249642 0.249642)
							(end -0.2794 0.1778)
						)
						(arc
							(start -0.2794 -0.1778)
							(mid -0.249642 -0.249642)
							(end -0.1778 -0.2794)
						)
						(arc
							(start 0.1778 -0.2794)
							(mid 0.249642 -0.249642)
							(end 0.2794 -0.1778)
						)
						(arc
							(start 0.2794 0.1778)
							(mid 0.249642 0.249642)
							(end 0.1778 0.2794)
						)
					)
					(width 0)
					(fill yes)
				)
			)
		)
		(pad "2" smd custom
			(at 0 0.4445 90)
			(size 0.1397 0.1397)
			(layers "B.Cu" "B.Mask" "B.Paste")
			(net "GND")
			(options
				(clearance outline)
				(anchor circle)
			)
			(primitives
				(gr_poly
					(pts
						(arc
							(start -0.1778 0.2794)
							(mid -0.249642 0.249642)
							(end -0.2794 0.1778)
						)
						(arc
							(start -0.2794 -0.1778)
							(mid -0.249642 -0.249642)
							(end -0.1778 -0.2794)
						)
						(arc
							(start 0.1778 -0.2794)
							(mid 0.249642 -0.249642)
							(end 0.2794 -0.1778)
						)
						(arc
							(start 0.2794 0.1778)
							(mid 0.249642 0.249642)
							(end 0.1778 0.2794)
						)
					)
					(width 0)
					(fill yes)
				)
			)
		)
	)
	(footprint ""
		(layer "B.Cu")
		(at 142.0622 -5.715)
		(property "Reference" "Q10"
			(at 0 0 0)
			(layer "B.SilkS")
			(hide yes)
			(effects
				(font
					(size 1.27 1.27)
				)
				(justify mirror)
			)
		)
		(property "Value" "SSM3K324R-GP"
			(at -0.127 -8.9662 0)
			(unlocked yes)
			(layer "B.Fab")
			(hide yes)
			(effects
				(font
					(size 1.016 1.016)
					(thickness 0.1524)
				)
				(justify mirror)
			)
		)
		(property "Device Type" "SOT23DGS2D4H35"
			(at -0.127 -10.4902 0)
			(unlocked yes)
			(layer "B.Fab")
			(hide yes)
			(effects
				(font
					(size 1.016 1.016)
					(thickness 0.1524)
				)
				(justify mirror)
			)
		)
		(duplicate_pad_numbers_are_jumpers no)
		(fp_line
			(start -1.651 -1.778)
			(end 1.651 -1.778)
			(stroke
				(width 0.1524)
				(type default)
			)
			(layer "B.SilkS")
		)
		(fp_line
			(start -1.651 1.778)
			(end -1.651 -1.778)
			(stroke
				(width 0.1524)
				(type default)
			)
			(layer "B.SilkS")
		)
		(fp_line
			(start 1.651 -1.778)
			(end 1.651 1.778)
			(stroke
				(width 0.1524)
				(type default)
			)
			(layer "B.SilkS")
		)
		(fp_line
			(start 1.651 1.778)
			(end -1.651 1.778)
			(stroke
				(width 0.1524)
				(type default)
			)
			(layer "B.SilkS")
		)
		(fp_poly
			(pts
				(xy 1.778 1.8796) (xy 1.778 -1.8796) (xy -1.778 -1.8796) (xy -1.778 1.8796)
			)
			(stroke
				(width 0)
				(type default)
			)
			(fill no)
			(layer "B.CrtYd")
		)
		(fp_poly
			(pts
				(xy 1.778 1.8796) (xy 1.778 -1.8796) (xy -1.778 -1.8796) (xy -1.778 1.8796)
			)
			(stroke
				(width 0)
				(type default)
			)
			(fill no)
			(layer "B.Fab")
		)
		(pad "D" smd custom
			(at 0 -0.9525 180)
			(size 0.1905 0.1905)
			(layers "B.Cu" "B.Mask" "B.Paste")
			(net "DRV_ACT_28_34_N")
			(options
				(clearance outline)
				(anchor circle)
			)
			(primitives
				(gr_poly
					(pts
						(arc
							(start -0.1778 -0.5715)
							(mid -0.321484 -0.511984)
							(end -0.381 -0.3683)
						)
						(arc
							(start -0.381 0.3683)
							(mid -0.321484 0.511984)
							(end -0.1778 0.5715)
						)
						(arc
							(start 0.1778 0.5715)
							(mid 0.321484 0.511984)
							(end 0.381 0.3683)
						)
						(arc
							(start 0.381 -0.3683)
							(mid 0.321484 -0.511984)
							(end 0.1778 -0.5715)
						)
					)
					(width 0)
					(fill yes)
				)
			)
		)
		(pad "G" smd custom
			(at 0.98425 0.9525 180)
			(size 0.1905 0.1905)
			(layers "B.Cu" "B.Mask" "B.Paste")
			(net "DRIVE_A_28_34_ACT")
			(options
				(clearance outline)
				(anchor circle)
			)
			(primitives
				(gr_poly
					(pts
						(arc
							(start -0.1778 -0.5715)
							(mid -0.321484 -0.511984)
							(end -0.381 -0.3683)
						)
						(arc
							(start -0.381 0.3683)
							(mid -0.321484 0.511984)
							(end -0.1778 0.5715)
						)
						(arc
							(start 0.1778 0.5715)
							(mid 0.321484 0.511984)
							(end 0.381 0.3683)
						)
						(arc
							(start 0.381 -0.3683)
							(mid 0.321484 -0.511984)
							(end 0.1778 -0.5715)
						)
					)
					(width 0)
					(fill yes)
				)
			)
		)
		(pad "S" smd custom
			(at -0.98425 0.9525 180)
			(size 0.1905 0.1905)
			(layers "B.Cu" "B.Mask" "B.Paste")
			(net "GND")
			(options
				(clearance outline)
				(anchor circle)
			)
			(primitives
				(gr_poly
					(pts
						(arc
							(start -0.1778 -0.5715)
							(mid -0.321484 -0.511984)
							(end -0.381 -0.3683)
						)
						(arc
							(start -0.381 0.3683)
							(mid -0.321484 0.511984)
							(end -0.1778 0.5715)
						)
						(arc
							(start 0.1778 0.5715)
							(mid 0.321484 0.511984)
							(end 0.381 0.3683)
						)
						(arc
							(start 0.381 -0.3683)
							(mid 0.321484 -0.511984)
							(end 0.1778 -0.5715)
						)
					)
					(width 0)
					(fill yes)
				)
			)
		)
	)
	(gr_line
		(start 0 -8.999982)
		(end 0 0)
		(stroke
			(width 0.05)
			(type default)
		)
		(layer "Edge.Cuts")
	)
	(gr_arc
		(start 0 -8.999982)
		(mid 0.292893 -9.707087)
		(end 0.999998 -9.99998)
		(stroke
			(width 0.05)
			(type default)
		)
		(layer "Edge.Cuts")
	)
	(gr_arc
		(start 0.999998 0.999998)
		(mid 0.292894 0.707105)
		(end 0 0)
		(stroke
			(width 0.05)
			(type default)
		)
		(layer "Edge.Cuts")
	)
	(gr_line
		(start 0.999998 0.999998)
		(end 183.999886 0.999998)
		(stroke
			(width 0.05)
			(type default)
		)
		(layer "Edge.Cuts")
	)
	(gr_arc
		(start 2.84988 -4.99999)
		(mid 4.12496 -6.27507)
		(end 5.40004 -4.99999)
		(stroke
			(width 0.05)
			(type default)
		)
		(layer "Edge.Cuts")
	)
	(gr_arc
		(start 5.40004 -4.99999)
		(mid 4.12496 -3.72491)
		(end 2.84988 -4.99999)
		(stroke
			(width 0.05)
			(type default)
		)
		(layer "Edge.Cuts")
	)
	(gr_line
		(start 8.599932 -9.99998)
		(end 0.999998 -9.99998)
		(stroke
			(width 0.05)
			(type default)
		)
		(layer "Edge.Cuts")
	)
	(gr_line
		(start 9.59993 -16.20012)
		(end 9.59993 -10.999978)
		(stroke
			(width 0.05)
			(type default)
		)
		(layer "Edge.Cuts")
	)
	(gr_arc
		(start 9.59993 -16.20012)
		(mid 9.892831 -16.907203)
		(end 10.599928 -17.200118)
		(stroke
			(width 0.05)
			(type default)
		)
		(layer "Edge.Cuts")
	)
	(gr_arc
		(start 9.59993 -10.999978)
		(mid 9.307037 -10.292873)
		(end 8.599932 -9.99998)
		(stroke
			(width 0.05)
			(type default)
		)
		(layer "Edge.Cuts")
	)
	(gr_arc
		(start 10.675112 -4.99999)
		(mid 12.125198 -6.450076)
		(end 13.57503 -4.99999)
		(stroke
			(width 0.05)
			(type default)
		)
		(layer "Edge.Cuts")
	)
	(gr_arc
		(start 13.57503 -4.99999)
		(mid 12.125198 -3.550158)
		(end 10.675112 -4.99999)
		(stroke
			(width 0.05)
			(type default)
		)
		(layer "Edge.Cuts")
	)
	(gr_line
		(start 16.599916 -17.200118)
		(end 10.599928 -17.200118)
		(stroke
			(width 0.05)
			(type default)
		)
		(layer "Edge.Cuts")
	)
	(gr_arc
		(start 16.599916 -17.200118)
		(mid 17.307018 -16.907221)
		(end 17.599914 -16.20012)
		(stroke
			(width 0.05)
			(type default)
		)
		(layer "Edge.Cuts")
	)
	(gr_line
		(start 17.599914 -10.999978)
		(end 17.599914 -16.20012)
		(stroke
			(width 0.05)
			(type default)
		)
		(layer "Edge.Cuts")
	)
	(gr_arc
		(start 18.599912 -9.99998)
		(mid 17.892807 -10.292873)
		(end 17.599914 -10.999978)
		(stroke
			(width 0.05)
			(type default)
		)
		(layer "Edge.Cuts")
	)
	(gr_line
		(start 39.649908 -9.99998)
		(end 18.599912 -9.99998)
		(stroke
			(width 0.05)
			(type default)
		)
		(layer "Edge.Cuts")
	)
	(gr_line
		(start 40.649906 -17.200118)
		(end 40.649906 -10.999978)
		(stroke
			(width 0.05)
			(type default)
		)
		(layer "Edge.Cuts")
	)
	(gr_arc
		(start 40.649906 -17.200118)
		(mid 40.942805 -17.90721)
		(end 41.649904 -18.200116)
		(stroke
			(width 0.05)
			(type default)
		)
		(layer "Edge.Cuts")
	)
	(gr_arc
		(start 40.649906 -10.999978)
		(mid 40.357013 -10.292873)
		(end 39.649908 -9.99998)
		(stroke
			(width 0.05)
			(type default)
		)
		(layer "Edge.Cuts")
	)
	(gr_line
		(start 56.649874 -18.200116)
		(end 41.649904 -18.200116)
		(stroke
			(width 0.05)
			(type default)
		)
		(layer "Edge.Cuts")
	)
	(gr_arc
		(start 56.649874 -18.200116)
		(mid 57.357132 -17.907304)
		(end 57.650126 -17.200118)
		(stroke
			(width 0.05)
			(type default)
		)
		(layer "Edge.Cuts")
	)
	(gr_line
		(start 57.650126 -10.999978)
		(end 57.650126 -17.200118)
		(stroke
			(width 0.05)
			(type default)
		)
		(layer "Edge.Cuts")
	)
	(gr_arc
		(start 58.650124 -9.99998)
		(mid 57.943019 -10.292873)
		(end 57.650126 -10.999978)
		(stroke
			(width 0.05)
			(type default)
		)
		(layer "Edge.Cuts")
	)
	(gr_line
		(start 71.699882 -9.99998)
		(end 58.650124 -9.99998)
		(stroke
			(width 0.05)
			(type default)
		)
		(layer "Edge.Cuts")
	)
	(gr_line
		(start 72.69988 -16.20012)
		(end 72.69988 -10.999978)
		(stroke
			(width 0.05)
			(type default)
		)
		(layer "Edge.Cuts")
	)
	(gr_arc
		(start 72.69988 -16.20012)
		(mid 72.992778 -16.90722)
		(end 73.699878 -17.200118)
		(stroke
			(width 0.05)
			(type default)
		)
		(layer "Edge.Cuts")
	)
	(gr_arc
		(start 72.69988 -10.999978)
		(mid 72.406987 -10.292873)
		(end 71.699882 -9.99998)
		(stroke
			(width 0.05)
			(type default)
		)
		(layer "Edge.Cuts")
	)
	(gr_arc
		(start 75.425046 -4.99999)
		(mid 76.700126 -6.27507)
		(end 77.974952 -4.99999)
		(stroke
			(width 0.05)
			(type default)
		)
		(layer "Edge.Cuts")
	)
	(gr_arc
		(start 77.974952 -4.99999)
		(mid 76.700126 -3.725164)
		(end 75.425046 -4.99999)
		(stroke
			(width 0.05)
			(type default)
		)
		(layer "Edge.Cuts")
	)
	(gr_line
		(start 79.70012 -17.200118)
		(end 73.699878 -17.200118)
		(stroke
			(width 0.05)
			(type default)
		)
		(layer "Edge.Cuts")
	)
	(gr_arc
		(start 79.70012 -17.200118)
		(mid 80.40722 -16.90722)
		(end 80.700118 -16.20012)
		(stroke
			(width 0.05)
			(type default)
		)
		(layer "Edge.Cuts")
	)
	(gr_line
		(start 80.700118 -10.999978)
		(end 80.700118 -16.20012)
		(stroke
			(width 0.05)
			(type default)
		)
		(layer "Edge.Cuts")
	)
	(gr_arc
		(start 81.700116 -9.99998)
		(mid 80.993011 -10.292873)
		(end 80.700118 -10.999978)
		(stroke
			(width 0.05)
			(type default)
		)
		(layer "Edge.Cuts")
	)
	(gr_line
		(start 103.249984 -9.99998)
		(end 81.700116 -9.99998)
		(stroke
			(width 0.05)
			(type default)
		)
		(layer "Edge.Cuts")
	)
	(gr_line
		(start 104.249982 -16.20012)
		(end 104.249982 -10.999978)
		(stroke
			(width 0.05)
			(type default)
		)
		(layer "Edge.Cuts")
	)
	(gr_arc
		(start 104.249982 -16.20012)
		(mid 104.54288 -16.90722)
		(end 105.24998 -17.200118)
		(stroke
			(width 0.05)
			(type default)
		)
		(layer "Edge.Cuts")
	)
	(gr_arc
		(start 104.249982 -10.999978)
		(mid 103.957089 -10.292873)
		(end 103.249984 -9.99998)
		(stroke
			(width 0.05)
			(type default)
		)
		(layer "Edge.Cuts")
	)
	(gr_line
		(start 111.249968 -17.200118)
		(end 105.24998 -17.200118)
		(stroke
			(width 0.05)
			(type default)
		)
		(layer "Edge.Cuts")
	)
	(gr_arc
		(start 111.249968 -17.200118)
		(mid 111.957101 -16.907238)
		(end 112.249966 -16.20012)
		(stroke
			(width 0.05)
			(type default)
		)
		(layer "Edge.Cuts")
	)
	(gr_line
		(start 112.249966 -10.999978)
		(end 112.249966 -16.20012)
		(stroke
			(width 0.05)
			(type default)
		)
		(layer "Edge.Cuts")
	)
	(gr_arc
		(start 113.249964 -9.99998)
		(mid 112.542859 -10.292873)
		(end 112.249966 -10.999978)
		(stroke
			(width 0.05)
			(type default)
		)
		(layer "Edge.Cuts")
	)
	(gr_arc
		(start 122.849894 -4.99999)
		(mid 124.124974 -6.27507)
		(end 125.400054 -4.99999)
		(stroke
			(width 0.05)
			(type default)
		)
		(layer "Edge.Cuts")
	)
	(gr_arc
		(start 125.400054 -4.99999)
		(mid 124.124974 -3.72491)
		(end 122.849894 -4.99999)
		(stroke
			(width 0.05)
			(type default)
		)
		(layer "Edge.Cuts")
	)
	(gr_line
		(start 134.800086 -9.99998)
		(end 113.249964 -9.99998)
		(stroke
			(width 0.05)
			(type default)
		)
		(layer "Edge.Cuts")
	)
	(gr_line
		(start 135.800084 -16.20012)
		(end 135.800084 -10.999978)
		(stroke
			(width 0.05)
			(type default)
		)
		(layer "Edge.Cuts")
	)
	(gr_arc
		(start 135.800084 -16.20012)
		(mid 136.092983 -16.907219)
		(end 136.800082 -17.200118)
		(stroke
			(width 0.05)
			(type default)
		)
		(layer "Edge.Cuts")
	)
	(gr_arc
		(start 135.800084 -10.999978)
		(mid 135.507191 -10.292873)
		(end 134.800086 -9.99998)
		(stroke
			(width 0.05)
			(type default)
		)
		(layer "Edge.Cuts")
	)
	(gr_line
		(start 142.80007 -17.200118)
		(end 136.800082 -17.200118)
		(stroke
			(width 0.05)
			(type default)
		)
		(layer "Edge.Cuts")
	)
	(gr_arc
		(start 142.80007 -17.200118)
		(mid 143.507202 -16.907237)
		(end 143.800068 -16.20012)
		(stroke
			(width 0.05)
			(type default)
		)
		(layer "Edge.Cuts")
	)
	(gr_line
		(start 143.800068 -10.999978)
		(end 143.800068 -16.20012)
		(stroke
			(width 0.05)
			(type default)
		)
		(layer "Edge.Cuts")
	)
	(gr_arc
		(start 144.800066 -9.99998)
		(mid 144.092961 -10.292873)
		(end 143.800068 -10.999978)
		(stroke
			(width 0.05)
			(type default)
		)
		(layer "Edge.Cuts")
	)
	(gr_line
		(start 166.349934 -9.99998)
		(end 144.800066 -9.99998)
		(stroke
			(width 0.05)
			(type default)
		)
		(layer "Edge.Cuts")
	)
	(gr_line
		(start 167.349932 -16.20012)
		(end 167.349932 -10.999978)
		(stroke
			(width 0.05)
			(type default)
		)
		(layer "Edge.Cuts")
	)
	(gr_arc
		(start 167.349932 -16.20012)
		(mid 167.642834 -16.907202)
		(end 168.34993 -17.200118)
		(stroke
			(width 0.05)
			(type default)
		)
		(layer "Edge.Cuts")
	)
	(gr_arc
		(start 167.349932 -10.999978)
		(mid 167.057039 -10.292873)
		(end 166.349934 -9.99998)
		(stroke
			(width 0.05)
			(type default)
		)
		(layer "Edge.Cuts")
	)
	(gr_arc
		(start 171.425108 -4.99999)
		(mid 172.875194 -6.450076)
		(end 174.325026 -4.99999)
		(stroke
			(width 0.05)
			(type default)
		)
		(layer "Edge.Cuts")
	)
	(gr_arc
		(start 174.325026 -4.99999)
		(mid 172.875194 -3.550158)
		(end 171.425108 -4.99999)
		(stroke
			(width 0.05)
			(type default)
		)
		(layer "Edge.Cuts")
	)
	(gr_line
		(start 174.349918 -17.200118)
		(end 168.34993 -17.200118)
		(stroke
			(width 0.05)
			(type default)
		)
		(layer "Edge.Cuts")
	)
	(gr_arc
		(start 174.349918 -17.200118)
		(mid 175.057019 -16.90722)
		(end 175.349916 -16.20012)
		(stroke
			(width 0.05)
			(type default)
		)
		(layer "Edge.Cuts")
	)
	(gr_line
		(start 175.349916 -10.999978)
		(end 175.349916 -16.20012)
		(stroke
			(width 0.05)
			(type default)
		)
		(layer "Edge.Cuts")
	)
	(gr_arc
		(start 176.349914 -9.99998)
		(mid 175.642809 -10.292873)
		(end 175.349916 -10.999978)
		(stroke
			(width 0.05)
			(type default)
		)
		(layer "Edge.Cuts")
	)
	(gr_arc
		(start 179.600098 -4.99999)
		(mid 180.875178 -6.27507)
		(end 182.150004 -4.99999)
		(stroke
			(width 0.05)
			(type default)
		)
		(layer "Edge.Cuts")
	)
	(gr_arc
		(start 182.150004 -4.99999)
		(mid 180.875178 -3.725164)
		(end 179.600098 -4.99999)
		(stroke
			(width 0.05)
			(type default)
		)
		(layer "Edge.Cuts")
	)
	(gr_line
		(start 183.999886 -9.99998)
		(end 176.349914 -9.99998)
		(stroke
			(width 0.05)
			(type default)
		)
		(layer "Edge.Cuts")
	)
	(gr_arc
		(start 183.999886 -9.99998)
		(mid 184.706994 -9.707091)
		(end 184.999884 -8.999982)
		(stroke
			(width 0.05)
			(type default)
		)
		(layer "Edge.Cuts")
	)
	(gr_arc
		(start 184.999884 0)
		(mid 184.706991 0.7071)
		(end 183.999886 0.999998)
		(stroke
			(width 0.05)
			(type default)
		)
		(layer "Edge.Cuts")
	)
	(gr_line
		(start 184.999884 0)
		(end 184.999884 -8.999982)
		(stroke
			(width 0.05)
			(type default)
		)
		(layer "Edge.Cuts")
	)
	(segment
		(start 56.326786 -13.560552)
		(end 54.853078 -15.03426)
		(width 1.016)
		(layer "F.Cu")
		(net "P5V_A")
	)
	(segment
		(start 25.4 -4.191)
		(end 24.1554 -4.191)
		(width 1.016)
		(layer "F.Cu")
		(net "P5V_A")
	)
	(segment
		(start 61.443108 -5.30098)
		(end 61.305186 -5.438902)
		(width 1.016)
		(layer "F.Cu")
		(net "P5V_A")
	)
	(segment
		(start 158.3436 -5.0038)
		(end 169.037 -5.0038)
		(width 1.016)
		(layer "F.Cu")
		(net "P5V_A")
	)
	(segment
		(start 24.1554 -4.191)
		(end 23.2918 -5.0546)
		(width 1.016)
		(layer "F.Cu")
		(net "P5V_A")
	)
	(segment
		(start 61.305186 -5.438902)
		(end 60.287916 -5.438902)
		(width 1.016)
		(layer "F.Cu")
		(net "P5V_A")
	)
	(segment
		(start 35.3822 -4.826)
		(end 26.035 -4.826)
		(width 1.016)
		(layer "F.Cu")
		(net "P5V_A")
	)
	(segment
		(start 145.5674 -5.1562)
		(end 145.6182 -5.207)
		(width 1.016)
		(layer "F.Cu")
		(net "P5V_A")
	)
	(segment
		(start 113.538 -5.2578)
		(end 102.87 -5.2578)
		(width 1.016)
		(layer "F.Cu")
		(net "P5V_A")
	)
	(segment
		(start 56.326786 -9.400032)
		(end 56.326786 -13.560552)
		(width 1.016)
		(layer "F.Cu")
		(net "P5V_A")
	)
	(segment
		(start 26.035 -4.826)
		(end 25.4 -4.191)
		(width 1.016)
		(layer "F.Cu")
		(net "P5V_A")
	)
	(segment
		(start 71.932038 -5.30098)
		(end 61.443108 -5.30098)
		(width 1.016)
		(layer "F.Cu")
		(net "P5V_A")
	)
	(segment
		(start 60.287916 -5.438902)
		(end 56.326786 -9.400032)
		(width 1.016)
		(layer "F.Cu")
		(net "P5V_A")
	)
	(segment
		(start 54.853078 -15.03426)
		(end 50.749708 -15.03426)
		(width 1.016)
		(layer "F.Cu")
		(net "P5V_A")
	)
	(segment
		(start 23.2918 -5.0546)
		(end 15.207234 -5.0546)
		(width 1.016)
		(layer "F.Cu")
		(net "P5V_A")
	)
	(segment
		(start 158.3182 -4.9784)
		(end 158.3436 -5.0038)
		(width 1.016)
		(layer "F.Cu")
		(net "P5V_A")
	)
	(segment
		(start 135.001 -5.1562)
		(end 145.5674 -5.1562)
		(width 1.016)
		(layer "F.Cu")
		(net "P5V_A")
	)
	(via
		(at 25.4 -4.191)
		(size 0.5588)
		(drill 0.3048)
		(layers "F.Cu" "B.Cu")
		(net "P5V_A")
	)
	(via
		(at 61.305186 -5.438902)
		(size 0.5588)
		(drill 0.3048)
		(layers "F.Cu" "B.Cu")
		(net "P5V_A")
	)
	(via
		(at 41.196514 -6.185154)
		(size 0.5588)
		(drill 0.3048)
		(layers "F.Cu" "B.Cu")
		(net "P5V_A")
	)
	(via
		(at 50.7238 -16.23314)
		(size 0.5588)
		(drill 0.3048)
		(layers "F.Cu" "B.Cu")
		(net "P5V_A")
	)
	(via
		(at 15.207234 -5.0546)
		(size 0.5588)
		(drill 0.3048)
		(layers "F.Cu" "B.Cu")
		(net "P5V_A")
	)
	(via
		(at 42.060622 -5.512054)
		(size 0.5588)
		(drill 0.3048)
		(layers "F.Cu" "B.Cu")
		(net "P5V_A")
	)
	(via
		(at 158.3182 -4.9784)
		(size 0.5588)
		(drill 0.3048)
		(layers "F.Cu" "B.Cu")
		(net "P5V_A")
	)
	(via
		(at 100.457 -5.207)
		(size 0.6096)
		(drill 0.3048)
		(layers "F.Cu" "B.Cu")
		(net "P5V_A")
	)
	(via
		(at 148.0058 -5.207)
		(size 0.6096)
		(drill 0.3048)
		(layers "F.Cu" "B.Cu")
		(net "P5V_A")
	)
	(via
		(at 102.87 -5.2578)
		(size 0.5588)
		(drill 0.3048)
		(layers "F.Cu" "B.Cu")
		(net "P5V_A")
	)
	(via
		(at 169.037 -5.0038)
		(size 0.5588)
		(drill 0.3048)
		(layers "F.Cu" "B.Cu")
		(net "P5V_A")
	)
	(via
		(at 48.641 -16.23314)
		(size 0.5588)
		(drill 0.3048)
		(layers "F.Cu" "B.Cu")
		(net "P5V_A")
	)
	(via
		(at 49.657 -16.23314)
		(size 0.5588)
		(drill 0.3048)
		(layers "F.Cu" "B.Cu")
		(net "P5V_A")
	)
	(via
		(at 113.538 -5.2578)
		(size 0.5588)
		(drill 0.3048)
		(layers "F.Cu" "B.Cu")
		(net "P5V_A")
	)
	(via
		(at 133.0706 -5.1562)
		(size 0.6096)
		(drill 0.3048)
		(layers "F.Cu" "B.Cu")
		(net "P5V_A")
	)
	(via
		(at 71.932038 -5.30098)
		(size 0.5588)
		(drill 0.3048)
		(layers "F.Cu" "B.Cu")
		(net "P5V_A")
	)
	(via
		(at 145.6182 -5.207)
		(size 0.5588)
		(drill 0.3048)
		(layers "F.Cu" "B.Cu")
		(net "P5V_A")
	)
	(via
		(at 35.3822 -4.826)
		(size 0.5588)
		(drill 0.3048)
		(layers "F.Cu" "B.Cu")
		(net "P5V_A")
	)
	(via
		(at 135.001 -5.1562)
		(size 0.5588)
		(drill 0.3048)
		(layers "F.Cu" "B.Cu")
		(net "P5V_A")
	)
	(segment
		(start 129.5654 -5.1562)
		(end 133.0706 -5.1562)
		(width 1.016)
		(layer "B.Cu")
		(net "P5V_A")
	)
	(segment
		(start 102.87 -5.2578)
		(end 102.8192 -5.207)
		(width 1.016)
		(layer "B.Cu")
		(net "P5V_A")
	)
	(segment
		(start 103.9876 -5.2578)
		(end 102.87 -5.2578)
		(width 0.762)
		(layer "B.Cu")
		(net "P5V_A")
	)
	(segment
		(start 126.038356 -8.683244)
		(end 129.5654 -5.1562)
		(width 1.016)
		(layer "B.Cu")
		(net "P5V_A")
	)
	(segment
		(start 112.395 -5.2578)
		(end 113.538 -5.2578)
		(width 0.762)
		(layer "B.Cu")
		(net "P5V_A")
	)
	(segment
		(start 70.757796 -5.30098)
		(end 71.932038 -5.30098)
		(width 0.762)
		(layer "B.Cu")
		(net "P5V_A")
	)
	(segment
		(start 102.8192 -5.207)
		(end 100.457 -5.207)
		(width 1.016)
		(layer "B.Cu")
		(net "P5V_A")
	)
	(segment
		(start 136.0678 -5.1562)
		(end 135.001 -5.1562)
		(width 0.762)
		(layer "B.Cu")
		(net "P5V_A")
	)
	(segment
		(start 75.3364 -8.975598)
		(end 78.579218 -8.975598)
		(width 1.016)
		(layer "B.Cu")
		(net "P5V_A")
	)
	(segment
		(start 158.3182 -4.9784)
		(end 158.0896 -5.207)
		(width 1.016)
		(layer "B.Cu")
		(net "P5V_A")
	)
	(segment
		(start 135.001 -5.1562)
		(end 133.0706 -5.1562)
		(width 1.016)
		(layer "B.Cu")
		(net "P5V_A")
	)
	(segment
		(start 116.8146 -5.2578)
		(end 120.240044 -8.683244)
		(width 1.016)
		(layer "B.Cu")
		(net "P5V_A")
	)
	(segment
		(start 82.347816 -5.207)
		(end 100.457 -5.207)
		(width 1.016)
		(layer "B.Cu")
		(net "P5V_A")
	)
	(segment
		(start 145.6182 -5.207)
		(end 148.0058 -5.207)
		(width 1.016)
		(layer "B.Cu")
		(net "P5V_A")
	)
	(segment
		(start 120.240044 -8.683244)
		(end 126.038356 -8.683244)
		(width 1.016)
		(layer "B.Cu")
		(net "P5V_A")
	)
	(segment
		(start 73.09866 -6.737858)
		(end 75.3364 -8.975598)
		(width 1.016)
		(layer "B.Cu")
		(net "P5V_A")
	)
	(segment
		(start 159.512 -4.9784)
		(end 158.3182 -4.9784)
		(width 0.762)
		(layer "B.Cu")
		(net "P5V_A")
	)
	(segment
		(start 167.9194 -5.0038)
		(end 169.037 -5.0038)
		(width 0.762)
		(layer "B.Cu")
		(net "P5V_A")
	)
	(segment
		(start 62.421262 -5.439918)
		(end 61.306202 -5.439918)
		(width 0.762)
		(layer "B.Cu")
		(net "P5V_A")
	)
	(segment
		(start 144.4752 -5.1308)
		(end 145.542 -5.1308)
		(width 0.762)
		(layer "B.Cu")
		(net "P5V_A")
	)
	(segment
		(start 158.0896 -5.207)
		(end 148.0058 -5.207)
		(width 1.016)
		(layer "B.Cu")
		(net "P5V_A")
	)
	(segment
		(start 16.3322 -5.0546)
		(end 15.207234 -5.0546)
		(width 0.762)
		(layer "B.Cu")
		(net "P5V_A")
	)
	(segment
		(start 113.538 -5.2578)
		(end 116.8146 -5.2578)
		(width 1.016)
		(layer "B.Cu")
		(net "P5V_A")
	)
	(segment
		(start 71.932038 -5.30098)
		(end 73.09866 -6.467602)
		(width 1.016)
		(layer "B.Cu")
		(net "P5V_A")
	)
	(segment
		(start 73.09866 -6.467602)
		(end 73.09866 -6.737858)
		(width 1.016)
		(layer "B.Cu")
		(net "P5V_A")
	)
	(segment
		(start 61.306202 -5.439918)
		(end 61.305186 -5.438902)
		(width 0.762)
		(layer "B.Cu")
		(net "P5V_A")
	)
	(segment
		(start 145.542 -5.1308)
		(end 145.6182 -5.207)
		(width 0.762)
		(layer "B.Cu")
		(net "P5V_A")
	)
	(segment
		(start 78.579218 -8.975598)
		(end 82.347816 -5.207)
		(width 1.016)
		(layer "B.Cu")
		(net "P5V_A")
	)
	(via
		(at 168.407588 -15.06728)
		(size 0.5588)
		(drill 0.3048)
		(layers "F.Cu" "B.Cu")
		(net "GND")
	)
	(via
		(at 176.761648 -4.673346)
		(size 0.5588)
		(drill 0.3048)
		(layers "F.Cu" "B.Cu")
		(net "GND")
	)
	(via
		(at 92.9132 -6.7056)
		(size 0.5588)
		(drill 0.3048)
		(layers "F.Cu" "B.Cu")
		(net "GND")
	)
	(via
		(at 142.736316 -14.949932)
		(size 0.5588)
		(drill 0.3048)
		(layers "F.Cu" "B.Cu")
		(net "GND")
	)
	(via
		(at 7.714996 -8.775954)
		(size 0.5588)
		(drill 0.3048)
		(layers "F.Cu" "B.Cu")
		(net "GND")
	)
	(via
		(at 36.982654 -0.06223)
		(size 0.5588)
		(drill 0.3048)
		(layers "F.Cu" "B.Cu")
		(net "GND")
	)
	(via
		(at 145.838672 -1.965198)
		(size 0.5588)
		(drill 0.3048)
		(layers "F.Cu" "B.Cu")
		(net "GND")
	)
	(via
		(at 62.446662 -8.03148)
		(size 0.5588)
		(drill 0.3048)
		(layers "F.Cu" "B.Cu")
		(net "GND")
	)
	(via
		(at 73.82764 -14.948154)
		(size 0.5588)
		(drill 0.3048)
		(layers "F.Cu" "B.Cu")
		(net "GND")
	)
	(via
		(at 156.819092 -1.95453)
		(size 0.5588)
		(drill 0.3048)
		(layers "F.Cu" "B.Cu")
		(net "GND")
	)
	(via
		(at 5.196586 -1.443228)
		(size 0.5588)
		(drill 0.3048)
		(layers "F.Cu" "B.Cu")
		(net "GND")
	)
	(via
		(at 120.375426 -2.728976)
		(size 0.5588)
		(drill 0.3048)
		(layers "F.Cu" "B.Cu")
		(net "GND")
	)
	(via
		(at 156.104844 -6.488176)
		(size 0.5588)
		(drill 0.3048)
		(layers "F.Cu" "B.Cu")
		(net "GND")
	)
	(via
		(at 28.933648 -0.06223)
		(size 0.5588)
		(drill 0.3048)
		(layers "F.Cu" "B.Cu")
		(net "GND")
	)
	(via
		(at 54.991 -17.145)
		(size 0.5588)
		(drill 0.3048)
		(layers "F.Cu" "B.Cu")
		(net "GND")
	)
	(via
		(at 21.4884 -3.048)
		(size 0.5588)
		(drill 0.3048)
		(layers "F.Cu" "B.Cu")
		(net "GND")
	)
	(via
		(at 137.47115 -3.5306)
		(size 0.5588)
		(drill 0.3048)
		(layers "F.Cu" "B.Cu")
		(net "GND")
	)
	(via
		(at 164.4904 -3.175)
		(size 0.5588)
		(drill 0.3048)
		(layers "F.Cu" "B.Cu")
		(net "GND")
	)
	(via
		(at 113.31829 -2.676398)
		(size 0.5588)
		(drill 0.3048)
		(layers "F.Cu" "B.Cu")
		(net "GND")
	)
	(via
		(at 63.439548 -3.288284)
		(size 0.5588)
		(drill 0.3048)
		(layers "F.Cu" "B.Cu")
		(net "GND")
	)
	(via
		(at 25.146 -8.89)
		(size 0.5588)
		(drill 0.3048)
		(layers "F.Cu" "B.Cu")
		(net "GND")
	)
	(via
		(at 170.487086 -11.553698)
		(size 0.6604)
		(drill 0.3302)
		(layers "F.Cu" "B.Cu")
		(net "GND")
	)
	(via
		(at 22.953472 -0.06223)
		(size 0.5588)
		(drill 0.3048)
		(layers "F.Cu" "B.Cu")
		(net "GND")
	)
	(via
		(at 131.789424 -6.498082)
		(size 0.5588)
		(drill 0.3048)
		(layers "F.Cu" "B.Cu")
		(net "GND")
	)
	(via
		(at 160.7566 -3.3782)
		(size 0.5588)
		(drill 0.3048)
		(layers "F.Cu" "B.Cu")
		(net "GND")
	)
	(via
		(at 107.352084 -11.774424)
		(size 0.6604)
		(drill 0.3302)
		(layers "F.Cu" "B.Cu")
		(net "GND")
	)
	(via
		(at 178.980084 -1.05029)
		(size 0.5588)
		(drill 0.3048)
		(layers "F.Cu" "B.Cu")
		(net "GND")
	)
	(via
		(at 51.316636 -1.078738)
		(size 0.5588)
		(drill 0.3048)
		(layers "F.Cu" "B.Cu")
		(net "GND")
	)
	(via
		(at 45.602398 -2.496566)
		(size 0.5588)
		(drill 0.3048)
		(layers "F.Cu" "B.Cu")
		(net "GND")
	)
	(via
		(at 83.8962 -6.604)
		(size 0.5588)
		(drill 0.3048)
		(layers "F.Cu" "B.Cu")
		(net "GND")
	)
	(via
		(at 117.574822 -8.933688)
		(size 0.5588)
		(drill 0.3048)
		(layers "F.Cu" "B.Cu")
		(net "GND")
	)
	(via
		(at 110.747048 -15.151354)
		(size 0.5588)
		(drill 0.3048)
		(layers "F.Cu" "B.Cu")
		(net "GND")
	)
	(via
		(at 100.1776 -6.6802)
		(size 0.5588)
		(drill 0.3048)
		(layers "F.Cu" "B.Cu")
		(net "GND")
	)
	(via
		(at 9.026906 -1.154684)
		(size 0.5588)
		(drill 0.3048)
		(layers "F.Cu" "B.Cu")
		(net "GND")
	)
	(via
		(at 60.64377 -6.761226)
		(size 0.5588)
		(drill 0.3048)
		(layers "F.Cu" "B.Cu")
		(net "GND")
	)
	(via
		(at 41.7068 -15.748)
		(size 0.5588)
		(drill 0.3048)
		(layers "F.Cu" "B.Cu")
		(net "GND")
	)
	(via
		(at 115.745006 -3.961892)
		(size 0.5588)
		(drill 0.3048)
		(layers "F.Cu" "B.Cu")
		(net "GND")
	)
	(via
		(at 152.78354 -0.070358)
		(size 0.5588)
		(drill 0.3048)
		(layers "F.Cu" "B.Cu")
		(net "GND")
	)
	(via
		(at 59.37631 -8.860282)
		(size 0.5588)
		(drill 0.3048)
		(layers "F.Cu" "B.Cu")
		(net "GND")
	)
	(via
		(at 13.722604 -7.33298)
		(size 0.5588)
		(drill 0.3048)
		(layers "F.Cu" "B.Cu")
		(net "GND")
	)
	(via
		(at 48.171608 -2.144776)
		(size 0.5588)
		(drill 0.3048)
		(layers "F.Cu" "B.Cu")
		(net "GND")
	)
	(via
		(at 50.2412 -17.145)
		(size 0.5588)
		(drill 0.3048)
		(layers "F.Cu" "B.Cu")
		(net "GND")
	)
	(via
		(at 135.14578 -2.572766)
		(size 0.5588)
		(drill 0.3048)
		(layers "F.Cu" "B.Cu")
		(net "GND")
	)
	(via
		(at 75.3364 -11.938)
		(size 0.6604)
		(drill 0.3302)
		(layers "F.Cu" "B.Cu")
		(net "GND")
	)
	(via
		(at 120.2182 -6.57225)
		(size 0.5588)
		(drill 0.3048)
		(layers "F.Cu" "B.Cu")
		(net "GND")
	)
	(via
		(at 143.663924 -9.150604)
		(size 0.5588)
		(drill 0.3048)
		(layers "F.Cu" "B.Cu")
		(net "GND")
	)
	(via
		(at 102.2096 -8.8392)
		(size 0.5588)
		(drill 0.3048)
		(layers "F.Cu" "B.Cu")
		(net "GND")
	)
	(via
		(at 105.3338 -3.5052)
		(size 0.5588)
		(drill 0.3048)
		(layers "F.Cu" "B.Cu")
		(net "GND")
	)
	(via
		(at 113.796826 -8.933688)
		(size 0.5588)
		(drill 0.3048)
		(layers "F.Cu" "B.Cu")
		(net "GND")
	)
	(via
		(at 60.551314 -3.666236)
		(size 0.5588)
		(drill 0.3048)
		(layers "F.Cu" "B.Cu")
		(net "GND")
	)
	(via
		(at 173.740064 -1.061212)
		(size 0.5588)
		(drill 0.3048)
		(layers "F.Cu" "B.Cu")
		(net "GND")
	)
	(via
		(at 13.622528 -11.589512)
		(size 0.6604)
		(drill 0.3302)
		(layers "F.Cu" "B.Cu")
		(net "GND")
	)
	(via
		(at 108.8644 -3.5052)
		(size 0.5588)
		(drill 0.3048)
		(layers "F.Cu" "B.Cu")
		(net "GND")
	)
	(via
		(at 56.5658 -15.2654)
		(size 0.5588)
		(drill 0.3048)
		(layers "F.Cu" "B.Cu")
		(net "GND")
	)
	(via
		(at 52.8066 -10.922)
		(size 0.6604)
		(drill 0.3302)
		(layers "F.Cu" "B.Cu")
		(net "GND")
	)
	(via
		(at 55.231284 -12.96289)
		(size 0.5588)
		(drill 0.3048)
		(layers "F.Cu" "B.Cu")
		(net "GND")
	)
	(via
		(at 55.849012 -8.14705)
		(size 0.5588)
		(drill 0.3048)
		(layers "F.Cu" "B.Cu")
		(net "GND")
	)
	(via
		(at 174.164244 -15.12062)
		(size 0.5588)
		(drill 0.3048)
		(layers "F.Cu" "B.Cu")
		(net "GND")
	)
	(via
		(at 97.6884 -8.8392)
		(size 0.5588)
		(drill 0.3048)
		(layers "F.Cu" "B.Cu")
		(net "GND")
	)
	(via
		(at 115.777518 -6.664198)
		(size 0.5588)
		(drill 0.3048)
		(layers "F.Cu" "B.Cu")
		(net "GND")
	)
	(via
		(at 70.90918 -8.95223)
		(size 0.5588)
		(drill 0.3048)
		(layers "F.Cu" "B.Cu")
		(net "GND")
	)
	(via
		(at 111.193072 -12.967208)
		(size 0.5588)
		(drill 0.3048)
		(layers "F.Cu" "B.Cu")
		(net "GND")
	)
	(via
		(at 174.366936 -9.976866)
		(size 0.5588)
		(drill 0.3048)
		(layers "F.Cu" "B.Cu")
		(net "GND")
	)
	(via
		(at 170.520868 -3.523488)
		(size 0.5588)
		(drill 0.3048)
		(layers "F.Cu" "B.Cu")
		(net "GND")
	)
	(via
		(at 57.271158 -5.239004)
		(size 0.5588)
		(drill 0.3048)
		(layers "F.Cu" "B.Cu")
		(net "GND")
	)
	(via
		(at 111.330994 -9.943592)
		(size 0.5588)
		(drill 0.3048)
		(layers "F.Cu" "B.Cu")
		(net "GND")
	)
	(via
		(at 98.4758 -6.0198)
		(size 0.6604)
		(drill 0.3302)
		(layers "F.Cu" "B.Cu")
		(net "GND")
	)
	(via
		(at 11.779504 -9.18464)
		(size 0.5588)
		(drill 0.3048)
		(layers "F.Cu" "B.Cu")
		(net "GND")
	)
	(via
		(at 55.231284 -11.89736)
		(size 0.5588)
		(drill 0.3048)
		(layers "F.Cu" "B.Cu")
		(net "GND")
	)
	(via
		(at 178.300634 -8.953246)
		(size 0.5588)
		(drill 0.3048)
		(layers "F.Cu" "B.Cu")
		(net "GND")
	)
	(via
		(at 183.871108 -8.894572)
		(size 0.5588)
		(drill 0.3048)
		(layers "F.Cu" "B.Cu")
		(net "GND")
	)
	(via
		(at 9.82345 -5.69595)
		(size 0.5588)
		(drill 0.3048)
		(layers "F.Cu" "B.Cu")
		(net "GND")
	)
	(via
		(at 24.7396 -6.1722)
		(size 0.6604)
		(drill 0.3302)
		(layers "F.Cu" "B.Cu")
		(net "GND")
	)
	(via
		(at 41.752012 -13.21308)
		(size 0.5588)
		(drill 0.3048)
		(layers "F.Cu" "B.Cu")
		(net "GND")
	)
	(via
		(at 102.7684 -3.6576)
		(size 0.5588)
		(drill 0.3048)
		(layers "F.Cu" "B.Cu")
		(net "GND")
	)
	(via
		(at 1.326642 -8.815324)
		(size 0.5588)
		(drill 0.3048)
		(layers "F.Cu" "B.Cu")
		(net "GND")
	)
	(via
		(at 127.4826 -2.628392)
		(size 0.5588)
		(drill 0.3048)
		(layers "F.Cu" "B.Cu")
		(net "GND")
	)
	(via
		(at 158.866078 -3.66014)
		(size 0.5588)
		(drill 0.3048)
		(layers "F.Cu" "B.Cu")
		(net "GND")
	)
	(via
		(at 86.2076 -8.8392)
		(size 0.5588)
		(drill 0.3048)
		(layers "F.Cu" "B.Cu")
		(net "GND")
	)
	(via
		(at 82.0928 -3.5052)
		(size 0.5588)
		(drill 0.3048)
		(layers "F.Cu" "B.Cu")
		(net "GND")
	)
	(via
		(at 136.894316 -15.06728)
		(size 0.5588)
		(drill 0.3048)
		(layers "F.Cu" "B.Cu")
		(net "GND")
	)
	(via
		(at 80.4672 -9.1186)
		(size 0.5588)
		(drill 0.3048)
		(layers "F.Cu" "B.Cu")
		(net "GND")
	)
	(via
		(at 16.51 -11.4554)
		(size 0.5588)
		(drill 0.3048)
		(layers "F.Cu" "B.Cu")
		(net "GND")
	)
	(via
		(at 134.614666 -8.918194)
		(size 0.5588)
		(drill 0.3048)
		(layers "F.Cu" "B.Cu")
		(net "GND")
	)
	(via
		(at 35.7886 -6.0452)
		(size 0.5588)
		(drill 0.3048)
		(layers "F.Cu" "B.Cu")
		(net "GND")
	)
	(via
		(at 36.8808 -6.6802)
		(size 0.5588)
		(drill 0.3048)
		(layers "F.Cu" "B.Cu")
		(net "GND")
	)
	(via
		(at 1.208532 -1.180846)
		(size 0.5588)
		(drill 0.3048)
		(layers "F.Cu" "B.Cu")
		(net "GND")
	)
	(via
		(at 44.333668 -1.06807)
		(size 0.5588)
		(drill 0.3048)
		(layers "F.Cu" "B.Cu")
		(net "GND")
	)
	(via
		(at 168.428924 -11.112246)
		(size 0.5588)
		(drill 0.3048)
		(layers "F.Cu" "B.Cu")
		(net "GND")
	)
	(via
		(at 147.352512 -3.76682)
		(size 0.5588)
		(drill 0.3048)
		(layers "F.Cu" "B.Cu")
		(net "GND")
	)
	(via
		(at 147.586954 -8.937244)
		(size 0.5588)
		(drill 0.3048)
		(layers "F.Cu" "B.Cu")
		(net "GND")
	)
	(via
		(at 31.623 -3.0734)
		(size 0.5588)
		(drill 0.3048)
		(layers "F.Cu" "B.Cu")
		(net "GND")
	)
	(via
		(at 163.589208 -8.953754)
		(size 0.5588)
		(drill 0.3048)
		(layers "F.Cu" "B.Cu")
		(net "GND")
	)
	(via
		(at 170.371262 -6.988556)
		(size 0.5588)
		(drill 0.3048)
		(layers "F.Cu" "B.Cu")
		(net "GND")
	)
	(via
		(at 97.4344 -3.556)
		(size 0.5588)
		(drill 0.3048)
		(layers "F.Cu" "B.Cu")
		(net "GND")
	)
	(via
		(at 79.5528 -11.557)
		(size 0.5588)
		(drill 0.3048)
		(layers "F.Cu" "B.Cu")
		(net "GND")
	)
	(via
		(at 131.245864 -4.04622)
		(size 0.5588)
		(drill 0.3048)
		(layers "F.Cu" "B.Cu")
		(net "GND")
	)
	(via
		(at 164.281358 -0.078994)
		(size 0.5588)
		(drill 0.3048)
		(layers "F.Cu" "B.Cu")
		(net "GND")
	)
	(via
		(at 139.204446 -11.789156)
		(size 0.6604)
		(drill 0.3302)
		(layers "F.Cu" "B.Cu")
		(net "GND")
	)
	(via
		(at 136.883394 -10.771124)
		(size 0.5588)
		(drill 0.3048)
		(layers "F.Cu" "B.Cu")
		(net "GND")
	)
	(via
		(at 140.843 -3.302)
		(size 0.5588)
		(drill 0.3048)
		(layers "F.Cu" "B.Cu")
		(net "GND")
	)
	(via
		(at 19.3548 -8.9408)
		(size 0.5588)
		(drill 0.3048)
		(layers "F.Cu" "B.Cu")
		(net "GND")
	)
	(via
		(at 18.034 -2.9464)
		(size 0.5588)
		(drill 0.3048)
		(layers "F.Cu" "B.Cu")
		(net "GND")
	)
	(via
		(at 28.2194 -2.6416)
		(size 0.5588)
		(drill 0.3048)
		(layers "F.Cu" "B.Cu")
		(net "GND")
	)
	(via
		(at 88.6206 -3.4798)
		(size 0.5588)
		(drill 0.3048)
		(layers "F.Cu" "B.Cu")
		(net "GND")
	)
	(via
		(at 10.653268 -11.904726)
		(size 0.5588)
		(drill 0.3048)
		(layers "F.Cu" "B.Cu")
		(net "GND")
	)
	(via
		(at 105.3084 -11.3284)
		(size 0.5588)
		(drill 0.3048)
		(layers "F.Cu" "B.Cu")
		(net "GND")
	)
	(via
		(at 105.3338 -14.732)
		(size 0.5588)
		(drill 0.3048)
		(layers "F.Cu" "B.Cu")
		(net "GND")
	)
	(via
		(at 16.5354 -14.986)
		(size 0.5588)
		(drill 0.3048)
		(layers "F.Cu" "B.Cu")
		(net "GND")
	)
	(via
		(at 147.323556 -6.445504)
		(size 0.5588)
		(drill 0.3048)
		(layers "F.Cu" "B.Cu")
		(net "GND")
	)
	(via
		(at 156.33954 -8.90524)
		(size 0.5588)
		(drill 0.3048)
		(layers "F.Cu" "B.Cu")
		(net "GND")
	)
	(via
		(at 79.629 -14.7574)
		(size 0.5588)
		(drill 0.3048)
		(layers "F.Cu" "B.Cu")
		(net "GND")
	)
	(via
		(at 44.6532 -17.145)
		(size 0.5588)
		(drill 0.3048)
		(layers "F.Cu" "B.Cu")
		(net "GND")
	)
	(via
		(at 65.190624 -8.938006)
		(size 0.5588)
		(drill 0.3048)
		(layers "F.Cu" "B.Cu")
		(net "GND")
	)
	(via
		(at 16.123158 -1.167892)
		(size 0.5588)
		(drill 0.3048)
		(layers "F.Cu" "B.Cu")
		(net "GND")
	)
	(via
		(at 143.010636 -0.079248)
		(size 0.5588)
		(drill 0.3048)
		(layers "F.Cu" "B.Cu")
		(net "GND")
	)
	(via
		(at 127.802386 -8.918194)
		(size 0.5588)
		(drill 0.3048)
		(layers "F.Cu" "B.Cu")
		(net "GND")
	)
	(via
		(at 142.651226 -12.178284)
		(size 0.5588)
		(drill 0.3048)
		(layers "F.Cu" "B.Cu")
		(net "GND")
	)
	(via
		(at 10.686034 -14.895576)
		(size 0.5588)
		(drill 0.3048)
		(layers "F.Cu" "B.Cu")
		(net "GND")
	)
	(via
		(at 183.940196 -1.133602)
		(size 0.5588)
		(drill 0.3048)
		(layers "F.Cu" "B.Cu")
		(net "GND")
	)
	(via
		(at 159.596582 -0.070612)
		(size 0.5588)
		(drill 0.3048)
		(layers "F.Cu" "B.Cu")
		(net "GND")
	)
	(via
		(at 73.7489 -11.75385)
		(size 0.5588)
		(drill 0.3048)
		(layers "F.Cu" "B.Cu")
		(net "GND")
	)
	(via
		(at 168.21785 -1.167638)
		(size 0.5588)
		(drill 0.3048)
		(layers "F.Cu" "B.Cu")
		(net "GND")
	)
	(via
		(at 67.320668 -3.325622)
		(size 0.5588)
		(drill 0.3048)
		(layers "F.Cu" "B.Cu")
		(net "GND")
	)
	(segment
		(start 67.320668 -3.325622)
		(end 67.320668 -4.626356)
		(width 0.508)
		(layer "B.Cu")
		(net "GND")
	)
	(segment
		(start 105.3338 -4.88315)
		(end 105.3338 -3.5052)
		(width 0.508)
		(layer "B.Cu")
		(net "GND")
	)
	(segment
		(start 27.46375 -3.39725)
		(end 27.46375 -4.1021)
		(width 0.508)
		(layer "B.Cu")
		(net "GND")
	)
	(segment
		(start 106.1847 -3.5052)
		(end 105.3338 -3.5052)
		(width 0.508)
		(layer "B.Cu")
		(net "GND")
	)
	(segment
		(start 63.418466 -4.305554)
		(end 63.418466 -3.309366)
		(width 0.508)
		(layer "B.Cu")
		(net "GND")
	)
	(segment
		(start 28.2194 -2.6416)
		(end 27.46375 -3.39725)
		(width 0.508)
		(layer "B.Cu")
		(net "GND")
	)
	(segment
		(start 17.9832 -2.9464)
		(end 18.034 -2.9464)
		(width 0.508)
		(layer "B.Cu")
		(net "GND")
	)
	(segment
		(start 32.0548 -2.6416)
		(end 31.623 -3.0734)
		(width 0.508)
		(layer "B.Cu")
		(net "GND")
	)
	(segment
		(start 109.7661 -3.5052)
		(end 108.8644 -3.5052)
		(width 0.508)
		(layer "B.Cu")
		(net "GND")
	)
	(segment
		(start 165.5191 -3.175)
		(end 164.4904 -3.175)
		(width 0.508)
		(layer "B.Cu")
		(net "GND")
	)
	(segment
		(start 68.191888 -3.247644)
		(end 67.398646 -3.247644)
		(width 0.508)
		(layer "B.Cu")
		(net "GND")
	)
	(segment
		(start 21.5392 -2.9972)
		(end 21.4884 -3.048)
		(width 0.508)
		(layer "B.Cu")
		(net "GND")
	)
	(segment
		(start 17.73555 -4.4577)
		(end 17.73555 -3.19405)
		(width 0.508)
		(layer "B.Cu")
		(net "GND")
	)
	(segment
		(start 63.418466 -3.309366)
		(end 63.439548 -3.288284)
		(width 0.508)
		(layer "B.Cu")
		(net "GND")
	)
	(segment
		(start 140.8684 -3.3274)
		(end 140.8684 -4.55295)
		(width 0.381)
		(layer "B.Cu")
		(net "GND")
	)
	(segment
		(start 108.8644 -3.5052)
		(end 108.8644 -4.80695)
		(width 0.508)
		(layer "B.Cu")
		(net "GND")
	)
	(segment
		(start 63.812928 -4.700016)
		(end 63.418466 -4.305554)
		(width 0.508)
		(layer "B.Cu")
		(net "GND")
	)
	(segment
		(start 31.623 -3.0734)
		(end 31.04515 -3.65125)
		(width 0.508)
		(layer "B.Cu")
		(net "GND")
	)
	(segment
		(start 32.4485 -2.6416)
		(end 32.0548 -2.6416)
		(width 0.508)
		(layer "B.Cu")
		(net "GND")
	)
	(segment
		(start 21.4884 -3.048)
		(end 21.31695 -3.21945)
		(width 0.508)
		(layer "B.Cu")
		(net "GND")
	)
	(segment
		(start 141.7955 -3.302)
		(end 140.843 -3.302)
		(width 0.381)
		(layer "B.Cu")
		(net "GND")
	)
	(segment
		(start 63.484506 -3.24358)
		(end 63.439802 -3.288284)
		(width 0.508)
		(layer "B.Cu")
		(net "GND")
	)
	(segment
		(start 138.3665 -3.302)
		(end 137.69975 -3.302)
		(width 0.381)
		(layer "B.Cu")
		(net "GND")
	)
	(segment
		(start 67.320668 -4.626356)
		(end 67.394328 -4.700016)
		(width 0.508)
		(layer "B.Cu")
		(net "GND")
	)
	(segment
		(start 31.04515 -3.65125)
		(end 31.04515 -4.1021)
		(width 0.508)
		(layer "B.Cu")
		(net "GND")
	)
	(segment
		(start 22.4409 -2.9972)
		(end 21.5392 -2.9972)
		(width 0.508)
		(layer "B.Cu")
		(net "GND")
	)
	(segment
		(start 63.439802 -3.288284)
		(end 63.439548 -3.288284)
		(width 0.508)
		(layer "B.Cu")
		(net "GND")
	)
	(segment
		(start 140.843 -3.302)
		(end 140.8684 -3.3274)
		(width 0.381)
		(layer "B.Cu")
		(net "GND")
	)
	(segment
		(start 105.41635 -4.9657)
		(end 105.3338 -4.88315)
		(width 0.508)
		(layer "B.Cu")
		(net "GND")
	)
	(segment
		(start 137.69975 -3.302)
		(end 137.47115 -3.5306)
		(width 0.381)
		(layer "B.Cu")
		(net "GND")
	)
	(segment
		(start 17.73555 -3.19405)
		(end 17.9832 -2.9464)
		(width 0.508)
		(layer "B.Cu")
		(net "GND")
	)
	(segment
		(start 140.8684 -4.55295)
		(end 141.07795 -4.7625)
		(width 0.381)
		(layer "B.Cu")
		(net "GND")
	)
	(segment
		(start 18.0848 -2.8956)
		(end 18.034 -2.9464)
		(width 0.508)
		(layer "B.Cu")
		(net "GND")
	)
	(segment
		(start 67.398646 -3.247644)
		(end 67.320668 -3.325622)
		(width 0.508)
		(layer "B.Cu")
		(net "GND")
	)
	(segment
		(start 21.31695 -3.21945)
		(end 21.31695 -4.4577)
		(width 0.508)
		(layer "B.Cu")
		(net "GND")
	)
	(segment
		(start 108.8644 -4.80695)
		(end 109.02315 -4.9657)
		(width 0.508)
		(layer "B.Cu")
		(net "GND")
	)
	(segment
		(start 64.252094 -3.24358)
		(end 63.484506 -3.24358)
		(width 0.508)
		(layer "B.Cu")
		(net "GND")
	)
	(segment
		(start 29.1973 -2.6416)
		(end 28.2194 -2.6416)
		(width 0.508)
		(layer "B.Cu")
		(net "GND")
	)
	(segment
		(start 164.4904 -3.175)
		(end 164.4904 -4.57835)
		(width 0.508)
		(layer "B.Cu")
		(net "GND")
	)
	(segment
		(start 164.4904 -4.57835)
		(end 164.54755 -4.6355)
		(width 0.508)
		(layer "B.Cu")
		(net "GND")
	)
	(segment
		(start 18.9103 -2.8956)
		(end 18.0848 -2.8956)
		(width 0.508)
		(layer "B.Cu")
		(net "GND")
	)
	(segment
		(start 137.47115 -3.5306)
		(end 137.47115 -4.7625)
		(width 0.381)
		(layer "B.Cu")
		(net "GND")
	)
	(segment
		(start 170.849544 -14.26972)
		(end 170.849544 -13.30452)
		(width 0.127)
		(layer "F.Cu")
		(net "FLT_HDD29_35_N")
	)
	(via
		(at 170.849544 -13.30452)
		(size 0.5588)
		(drill 0.3048)
		(layers "F.Cu" "B.Cu")
		(net "FLT_HDD29_35_N")
	)
	(via
		(at 170.849544 -12.2174)
		(size 0.6096)
		(drill 0.3048)
		(layers "F.Cu" "B.Cu")
		(net "FLT_HDD29_35_N")
	)
	(segment
		(start 161.925 -7.0358)
		(end 162.832034 -7.942834)
		(width 0.127)
		(layer "B.Cu")
		(net "FLT_HDD29_35_N")
	)
	(segment
		(start 161.925 -6.5405)
		(end 161.925 -7.0358)
		(width 0.127)
		(layer "B.Cu")
		(net "FLT_HDD29_35_N")
	)
	(segment
		(start 170.849544 -10.558526)
		(end 170.849544 -12.2174)
		(width 0.127)
		(layer "B.Cu")
		(net "FLT_HDD29_35_N")
	)
	(segment
		(start 168.233852 -7.942834)
		(end 170.849544 -10.558526)
		(width 0.127)
		(layer "B.Cu")
		(net "FLT_HDD29_35_N")
	)
	(segment
		(start 170.849544 -12.2174)
		(end 170.849544 -13.30452)
		(width 0.127)
		(layer "B.Cu")
		(net "FLT_HDD29_35_N")
	)
	(segment
		(start 162.832034 -7.942834)
		(end 168.233852 -7.942834)
		(width 0.127)
		(layer "B.Cu")
		(net "FLT_HDD29_35_N")
	)
	(segment
		(start 169.766742 -13.798804)
		(end 169.766742 -14.90218)
		(width 0.127)
		(layer "F.Cu")
		(net "FLT_HDD29_35")
	)
	(segment
		(start 169.766742 -14.90218)
		(end 170.594782 -15.73022)
		(width 0.127)
		(layer "F.Cu")
		(net "FLT_HDD29_35")
	)
	(segment
		(start 170.594782 -15.73022)
		(end 170.849544 -15.73022)
		(width 0.127)
		(layer "F.Cu")
		(net "FLT_HDD29_35")
	)
	(via
		(at 169.766742 -13.798804)
		(size 0.5588)
		(drill 0.3048)
		(layers "F.Cu" "B.Cu")
		(net "FLT_HDD29_35")
	)
	(via
		(at 169.763694 -11.156696)
		(size 0.6096)
		(drill 0.3048)
		(layers "F.Cu" "B.Cu")
		(net "FLT_HDD29_35")
	)
	(segment
		(start 159.512 -6.5024)
		(end 159.512 -7.239)
		(width 0.127)
		(layer "B.Cu")
		(net "FLT_HDD29_35")
	)
	(segment
		(start 169.763694 -13.795756)
		(end 169.763694 -11.156696)
		(width 0.127)
		(layer "B.Cu")
		(net "FLT_HDD29_35")
	)
	(segment
		(start 169.766742 -13.798804)
		(end 169.763694 -13.795756)
		(width 0.127)
		(layer "B.Cu")
		(net "FLT_HDD29_35")
	)
	(segment
		(start 159.512 -7.239)
		(end 160.583626 -8.310626)
		(width 0.127)
		(layer "B.Cu")
		(net "FLT_HDD29_35")
	)
	(segment
		(start 160.583626 -8.310626)
		(end 167.898064 -8.310626)
		(width 0.127)
		(layer "B.Cu")
		(net "FLT_HDD29_35")
	)
	(segment
		(start 169.763694 -10.176256)
		(end 169.763694 -11.156696)
		(width 0.127)
		(layer "B.Cu")
		(net "FLT_HDD29_35")
	)
	(segment
		(start 167.898064 -8.310626)
		(end 169.763694 -10.176256)
		(width 0.127)
		(layer "B.Cu")
		(net "FLT_HDD29_35")
	)
	(segment
		(start 139.299696 -14.26972)
		(end 139.299696 -13.208)
		(width 0.127)
		(layer "F.Cu")
		(net "FLT_HDD28_34_N")
	)
	(via
		(at 139.299696 -13.208)
		(size 0.5588)
		(drill 0.3048)
		(layers "F.Cu" "B.Cu")
		(net "FLT_HDD28_34_N")
	)
	(via
		(at 139.299696 -11.9634)
		(size 0.6096)
		(drill 0.3048)
		(layers "F.Cu" "B.Cu")
		(net "FLT_HDD28_34_N")
	)
	(segment
		(start 138.4554 -7.9248)
		(end 139.299696 -8.769096)
		(width 0.127)
		(layer "B.Cu")
		(net "FLT_HDD28_34_N")
	)
	(segment
		(start 139.299696 -13.208)
		(end 139.299696 -11.9634)
		(width 0.127)
		(layer "B.Cu")
		(net "FLT_HDD28_34_N")
	)
	(segment
		(start 139.299696 -8.769096)
		(end 139.299696 -11.9634)
		(width 0.127)
		(layer "B.Cu")
		(net "FLT_HDD28_34_N")
	)
	(segment
		(start 138.4554 -6.6675)
		(end 138.4554 -7.9248)
		(width 0.127)
		(layer "B.Cu")
		(net "FLT_HDD28_34_N")
	)
	(segment
		(start 138.79322 -15.73022)
		(end 139.299696 -15.73022)
		(width 0.127)
		(layer "F.Cu")
		(net "FLT_HDD28_34")
	)
	(segment
		(start 138.3792 -13.859002)
		(end 138.3792 -15.3162)
		(width 0.127)
		(layer "F.Cu")
		(net "FLT_HDD28_34")
	)
	(segment
		(start 138.376406 -13.856208)
		(end 138.3792 -13.859002)
		(width 0.127)
		(layer "F.Cu")
		(net "FLT_HDD28_34")
	)
	(segment
		(start 138.3792 -15.3162)
		(end 138.79322 -15.73022)
		(width 0.127)
		(layer "F.Cu")
		(net "FLT_HDD28_34")
	)
	(via
		(at 138.376406 -13.856208)
		(size 0.5588)
		(drill 0.3048)
		(layers "F.Cu" "B.Cu")
		(net "FLT_HDD28_34")
	)
	(via
		(at 138.451336 -10.533888)
		(size 0.6096)
		(drill 0.3048)
		(layers "F.Cu" "B.Cu")
		(net "FLT_HDD28_34")
	)
	(segment
		(start 136.0678 -6.6802)
		(end 136.0678 -7.366)
		(width 0.127)
		(layer "B.Cu")
		(net "FLT_HDD28_34")
	)
	(segment
		(start 136.0678 -7.366)
		(end 138.451336 -9.749536)
		(width 0.127)
		(layer "B.Cu")
		(net "FLT_HDD28_34")
	)
	(segment
		(start 138.451336 -13.781278)
		(end 138.451336 -10.533888)
		(width 0.127)
		(layer "B.Cu")
		(net "FLT_HDD28_34")
	)
	(segment
		(start 138.451336 -9.749536)
		(end 138.451336 -10.533888)
		(width 0.127)
		(layer "B.Cu")
		(net "FLT_HDD28_34")
	)
	(segment
		(start 138.376406 -13.856208)
		(end 138.451336 -13.781278)
		(width 0.127)
		(layer "B.Cu")
		(net "FLT_HDD28_34")
	)
	(segment
		(start 107.749594 -14.26972)
		(end 107.749594 -13.208)
		(width 0.127)
		(layer "F.Cu")
		(net "FLT_HDD27_33_N")
	)
	(via
		(at 107.749594 -13.208)
		(size 0.5588)
		(drill 0.3048)
		(layers "F.Cu" "B.Cu")
		(net "FLT_HDD27_33_N")
	)
	(via
		(at 107.762802 -9.648444)
		(size 0.6096)
		(drill 0.3048)
		(layers "F.Cu" "B.Cu")
		(net "FLT_HDD27_33_N")
	)
	(segment
		(start 106.4006 -6.8707)
		(end 106.4006 -7.7216)
		(width 0.127)
		(layer "B.Cu")
		(net "FLT_HDD27_33_N")
	)
	(segment
		(start 107.749594 -13.208)
		(end 107.762802 -13.194792)
		(width 0.127)
		(layer "B.Cu")
		(net "FLT_HDD27_33_N")
	)
	(segment
		(start 106.4006 -7.7216)
		(end 107.762802 -9.083802)
		(width 0.127)
		(layer "B.Cu")
		(net "FLT_HDD27_33_N")
	)
	(segment
		(start 107.762802 -9.083802)
		(end 107.762802 -9.648444)
		(width 0.127)
		(layer "B.Cu")
		(net "FLT_HDD27_33_N")
	)
	(segment
		(start 107.762802 -13.194792)
		(end 107.762802 -9.648444)
		(width 0.127)
		(layer "B.Cu")
		(net "FLT_HDD27_33_N")
	)
	(segment
		(start 107.236768 -15.73022)
		(end 107.749594 -15.73022)
		(width 0.127)
		(layer "F.Cu")
		(net "FLT_HDD27_33")
	)
	(segment
		(start 106.84129 -13.852652)
		(end 106.84129 -15.334742)
		(width 0.127)
		(layer "F.Cu")
		(net "FLT_HDD27_33")
	)
	(segment
		(start 106.84129 -15.334742)
		(end 107.236768 -15.73022)
		(width 0.127)
		(layer "F.Cu")
		(net "FLT_HDD27_33")
	)
	(via
		(at 106.910378 -11.87196)
		(size 0.6096)
		(drill 0.3048)
		(layers "F.Cu" "B.Cu")
		(net "FLT_HDD27_33")
	)
	(via
		(at 106.84129 -13.852652)
		(size 0.5588)
		(drill 0.3048)
		(layers "F.Cu" "B.Cu")
		(net "FLT_HDD27_33")
	)
	(segment
		(start 106.84129 -13.852652)
		(end 106.910378 -13.783564)
		(width 0.127)
		(layer "B.Cu")
		(net "FLT_HDD27_33")
	)
	(segment
		(start 103.9876 -7.1882)
		(end 106.910378 -10.110978)
		(width 0.127)
		(layer "B.Cu")
		(net "FLT_HDD27_33")
	)
	(segment
		(start 106.910378 -13.783564)
		(end 106.910378 -11.87196)
		(width 0.127)
		(layer "B.Cu")
		(net "FLT_HDD27_33")
	)
	(segment
		(start 103.9876 -6.7818)
		(end 103.9876 -7.1882)
		(width 0.127)
		(layer "B.Cu")
		(net "FLT_HDD27_33")
	)
	(segment
		(start 106.910378 -10.110978)
		(end 106.910378 -11.87196)
		(width 0.127)
		(layer "B.Cu")
		(net "FLT_HDD27_33")
	)
	(segment
		(start 77.238352 -12.265914)
		(end 76.859638 -12.265914)
		(width 0.127)
		(layer "F.Cu")
		(net "FLT_HDD26_32_N")
	)
	(segment
		(start 76.199746 -12.925806)
		(end 76.199746 -14.26972)
		(width 0.127)
		(layer "F.Cu")
		(net "FLT_HDD26_32_N")
	)
	(segment
		(start 76.859638 -12.265914)
		(end 76.199746 -12.925806)
		(width 0.127)
		(layer "F.Cu")
		(net "FLT_HDD26_32_N")
	)
	(via
		(at 77.238352 -12.265914)
		(size 0.5588)
		(drill 0.3048)
		(layers "F.Cu" "B.Cu")
		(net "FLT_HDD26_32_N")
	)
	(via
		(at 76.288646 -10.521442)
		(size 0.6096)
		(drill 0.3048)
		(layers "F.Cu" "B.Cu")
		(net "FLT_HDD26_32_N")
	)
	(segment
		(start 69.071236 -7.481824)
		(end 71.99249 -7.481824)
		(width 0.127)
		(layer "B.Cu")
		(net "FLT_HDD26_32_N")
	)
	(segment
		(start 71.99249 -7.481824)
		(end 75.032108 -10.521442)
		(width 0.127)
		(layer "B.Cu")
		(net "FLT_HDD26_32_N")
	)
	(segment
		(start 77.238352 -12.265914)
		(end 77.238352 -11.471148)
		(width 0.127)
		(layer "B.Cu")
		(net "FLT_HDD26_32_N")
	)
	(segment
		(start 75.032108 -10.521442)
		(end 76.288646 -10.521442)
		(width 0.127)
		(layer "B.Cu")
		(net "FLT_HDD26_32_N")
	)
	(segment
		(start 77.238352 -11.471148)
		(end 76.288646 -10.521442)
		(width 0.127)
		(layer "B.Cu")
		(net "FLT_HDD26_32_N")
	)
	(segment
		(start 68.378578 -6.605016)
		(end 68.378578 -6.789166)
		(width 0.127)
		(layer "B.Cu")
		(net "FLT_HDD26_32_N")
	)
	(segment
		(start 68.378578 -6.789166)
		(end 69.071236 -7.481824)
		(width 0.127)
		(layer "B.Cu")
		(net "FLT_HDD26_32_N")
	)
	(segment
		(start 75.18527 -14.98727)
		(end 75.92822 -15.73022)
		(width 0.127)
		(layer "F.Cu")
		(net "FLT_HDD26_32")
	)
	(segment
		(start 75.18527 -13.977366)
		(end 75.18527 -14.98727)
		(width 0.127)
		(layer "F.Cu")
		(net "FLT_HDD26_32")
	)
	(segment
		(start 75.92822 -15.73022)
		(end 76.199746 -15.73022)
		(width 0.127)
		(layer "F.Cu")
		(net "FLT_HDD26_32")
	)
	(via
		(at 75.29195 -12.564872)
		(size 0.6096)
		(drill 0.3048)
		(layers "F.Cu" "B.Cu")
		(net "FLT_HDD26_32")
	)
	(via
		(at 75.18527 -13.977366)
		(size 0.5588)
		(drill 0.3048)
		(layers "F.Cu" "B.Cu")
		(net "FLT_HDD26_32")
	)
	(segment
		(start 75.29195 -11.787124)
		(end 75.29195 -12.564872)
		(width 0.127)
		(layer "B.Cu")
		(net "FLT_HDD26_32")
	)
	(segment
		(start 63.310262 -6.963918)
		(end 64.541654 -8.19531)
		(width 0.127)
		(layer "B.Cu")
		(net "FLT_HDD26_32")
	)
	(segment
		(start 75.18527 -13.977366)
		(end 75.29195 -13.870686)
		(width 0.127)
		(layer "B.Cu")
		(net "FLT_HDD26_32")
	)
	(segment
		(start 64.541654 -8.19531)
		(end 71.700136 -8.19531)
		(width 0.127)
		(layer "B.Cu")
		(net "FLT_HDD26_32")
	)
	(segment
		(start 75.29195 -13.870686)
		(end 75.29195 -12.564872)
		(width 0.127)
		(layer "B.Cu")
		(net "FLT_HDD26_32")
	)
	(segment
		(start 71.700136 -8.19531)
		(end 75.29195 -11.787124)
		(width 0.127)
		(layer "B.Cu")
		(net "FLT_HDD26_32")
	)
	(segment
		(start 62.421262 -6.963918)
		(end 63.310262 -6.963918)
		(width 0.127)
		(layer "B.Cu")
		(net "FLT_HDD26_32")
	)
	(segment
		(start 44.649644 -14.26972)
		(end 44.649644 -12.279376)
		(width 0.127)
		(layer "F.Cu")
		(net "FLT_HDD25_31_N")
	)
	(segment
		(start 29.539184 -8.725408)
		(end 41.095676 -8.725408)
		(width 0.127)
		(layer "F.Cu")
		(net "FLT_HDD25_31_N")
	)
	(segment
		(start 28.454096 -7.64032)
		(end 29.539184 -8.725408)
		(width 0.127)
		(layer "F.Cu")
		(net "FLT_HDD25_31_N")
	)
	(segment
		(start 41.095676 -8.725408)
		(end 43.585384 -11.215116)
		(width 0.127)
		(layer "F.Cu")
		(net "FLT_HDD25_31_N")
	)
	(segment
		(start 44.649644 -12.279376)
		(end 43.585384 -11.215116)
		(width 0.127)
		(layer "F.Cu")
		(net "FLT_HDD25_31_N")
	)
	(via
		(at 43.585384 -11.215116)
		(size 0.6604)
		(drill 0.3302)
		(layers "F.Cu" "B.Cu")
		(net "FLT_HDD25_31_N")
	)
	(via
		(at 28.454096 -7.64032)
		(size 0.5588)
		(drill 0.3048)
		(layers "F.Cu" "B.Cu")
		(net "FLT_HDD25_31_N")
	)
	(segment
		(start 28.448 -7.105904)
		(end 28.454096 -7.112)
		(width 0.127)
		(layer "B.Cu")
		(net "FLT_HDD25_31_N")
	)
	(segment
		(start 28.454096 -7.112)
		(end 28.454096 -7.64032)
		(width 0.127)
		(layer "B.Cu")
		(net "FLT_HDD25_31_N")
	)
	(segment
		(start 28.448 -6.0071)
		(end 28.448 -7.105904)
		(width 0.127)
		(layer "B.Cu")
		(net "FLT_HDD25_31_N")
	)
	(segment
		(start 43.988482 -12.97432)
		(end 43.984926 -12.970764)
		(width 0.127)
		(layer "F.Cu")
		(net "FLT_HDD25_31")
	)
	(segment
		(start 43.984926 -12.502388)
		(end 43.984926 -12.6238)
		(width 0.127)
		(layer "F.Cu")
		(net "FLT_HDD25_31")
	)
	(segment
		(start 44.235878 -15.73022)
		(end 43.988482 -15.482824)
		(width 0.127)
		(layer "F.Cu")
		(net "FLT_HDD25_31")
	)
	(segment
		(start 26.056844 -7.677658)
		(end 27.525218 -9.146032)
		(width 0.127)
		(layer "F.Cu")
		(net "FLT_HDD25_31")
	)
	(segment
		(start 44.649644 -15.73022)
		(end 44.235878 -15.73022)
		(width 0.127)
		(layer "F.Cu")
		(net "FLT_HDD25_31")
	)
	(segment
		(start 27.525218 -9.146032)
		(end 40.62857 -9.146032)
		(width 0.127)
		(layer "F.Cu")
		(net "FLT_HDD25_31")
	)
	(segment
		(start 43.984926 -12.970764)
		(end 43.984926 -12.6238)
		(width 0.127)
		(layer "F.Cu")
		(net "FLT_HDD25_31")
	)
	(segment
		(start 40.62857 -9.146032)
		(end 43.984926 -12.502388)
		(width 0.127)
		(layer "F.Cu")
		(net "FLT_HDD25_31")
	)
	(segment
		(start 43.988482 -15.482824)
		(end 43.988482 -12.97432)
		(width 0.127)
		(layer "F.Cu")
		(net "FLT_HDD25_31")
	)
	(via
		(at 43.984926 -12.6238)
		(size 0.6604)
		(drill 0.3302)
		(layers "F.Cu" "B.Cu")
		(net "FLT_HDD25_31")
	)
	(via
		(at 26.056844 -7.677658)
		(size 0.5588)
		(drill 0.3048)
		(layers "F.Cu" "B.Cu")
		(net "FLT_HDD25_31")
	)
	(segment
		(start 26.0604 -7.674102)
		(end 26.056844 -7.677658)
		(width 0.127)
		(layer "B.Cu")
		(net "FLT_HDD25_31")
	)
	(segment
		(start 26.0604 -6.7056)
		(end 26.0604 -7.674102)
		(width 0.127)
		(layer "B.Cu")
		(net "FLT_HDD25_31")
	)
	(segment
		(start 13.099542 -14.26972)
		(end 13.099542 -13.099542)
		(width 0.127)
		(layer "F.Cu")
		(net "FLT_HDD24_30_N")
	)
	(via
		(at 13.099542 -12.1158)
		(size 0.6096)
		(drill 0.3048)
		(layers "F.Cu" "B.Cu")
		(net "FLT_HDD24_30_N")
	)
	(via
		(at 13.099542 -13.099542)
		(size 0.5588)
		(drill 0.3048)
		(layers "F.Cu" "B.Cu")
		(net "FLT_HDD24_30_N")
	)
	(segment
		(start 17.881092 -6.3627)
		(end 13.099542 -11.14425)
		(width 0.127)
		(layer "B.Cu")
		(net "FLT_HDD24_30_N")
	)
	(segment
		(start 13.099542 -11.14425)
		(end 13.099542 -12.1158)
		(width 0.127)
		(layer "B.Cu")
		(net "FLT_HDD24_30_N")
	)
	(segment
		(start 18.7198 -6.3627)
		(end 17.881092 -6.3627)
		(width 0.127)
		(layer "B.Cu")
		(net "FLT_HDD24_30_N")
	)
	(segment
		(start 13.099542 -12.1158)
		(end 13.099542 -13.099542)
		(width 0.127)
		(layer "B.Cu")
		(net "FLT_HDD24_30_N")
	)
	(segment
		(start 12.1412 -14.9352)
		(end 12.93622 -15.73022)
		(width 0.127)
		(layer "F.Cu")
		(net "FLT_HDD24_30")
	)
	(segment
		(start 12.93622 -15.73022)
		(end 13.099542 -15.73022)
		(width 0.127)
		(layer "F.Cu")
		(net "FLT_HDD24_30")
	)
	(segment
		(start 12.1412 -14.351)
		(end 12.1412 -14.9352)
		(width 0.127)
		(layer "F.Cu")
		(net "FLT_HDD24_30")
	)
	(via
		(at 12.1412 -13.081)
		(size 0.6096)
		(drill 0.3048)
		(layers "F.Cu" "B.Cu")
		(net "FLT_HDD24_30")
	)
	(via
		(at 12.1412 -14.351)
		(size 0.5588)
		(drill 0.3048)
		(layers "F.Cu" "B.Cu")
		(net "FLT_HDD24_30")
	)
	(segment
		(start 16.3322 -7.0358)
		(end 12.1412 -11.2268)
		(width 0.127)
		(layer "B.Cu")
		(net "FLT_HDD24_30")
	)
	(segment
		(start 12.1412 -13.081)
		(end 12.1412 -14.351)
		(width 0.127)
		(layer "B.Cu")
		(net "FLT_HDD24_30")
	)
	(segment
		(start 16.3322 -6.5786)
		(end 16.3322 -7.0358)
		(width 0.127)
		(layer "B.Cu")
		(net "FLT_HDD24_30")
	)
	(segment
		(start 12.1412 -11.2268)
		(end 12.1412 -13.081)
		(width 0.127)
		(layer "B.Cu")
		(net "FLT_HDD24_30")
	)
	(segment
		(start 171.850304 -14.26972)
		(end 171.850304 -13.30452)
		(width 0.127)
		(layer "F.Cu")
		(net "DRV_ACT_29_35_N")
	)
	(via
		(at 171.850304 -11.3284)
		(size 0.6096)
		(drill 0.3048)
		(layers "F.Cu" "B.Cu")
		(net "DRV_ACT_29_35_N")
	)
	(via
		(at 171.850304 -13.30452)
		(size 0.5588)
		(drill 0.3048)
		(layers "F.Cu" "B.Cu")
		(net "DRV_ACT_29_35_N")
	)
	(segment
		(start 165.8112 -7.5692)
		(end 168.54932 -7.5692)
		(width 0.127)
		(layer "B.Cu")
		(net "DRV_ACT_29_35_N")
	)
	(segment
		(start 168.54932 -7.5692)
		(end 171.850304 -10.870184)
		(width 0.127)
		(layer "B.Cu")
		(net "DRV_ACT_29_35_N")
	)
	(segment
		(start 165.5318 -6.5405)
		(end 165.5318 -7.2898)
		(width 0.127)
		(layer "B.Cu")
		(net "DRV_ACT_29_35_N")
	)
	(segment
		(start 165.5318 -7.2898)
		(end 165.8112 -7.5692)
		(width 0.127)
		(layer "B.Cu")
		(net "DRV_ACT_29_35_N")
	)
	(segment
		(start 171.850304 -13.30452)
		(end 171.850304 -11.3284)
		(width 0.127)
		(layer "B.Cu")
		(net "DRV_ACT_29_35_N")
	)
	(segment
		(start 171.850304 -10.870184)
		(end 171.850304 -11.3284)
		(width 0.127)
		(layer "B.Cu")
		(net "DRV_ACT_29_35_N")
	)
	(segment
		(start 172.768006 -15.349728)
		(end 172.387514 -15.73022)
		(width 0.127)
		(layer "F.Cu")
		(net "DRV_ACT_29_35")
	)
	(segment
		(start 172.387514 -15.73022)
		(end 171.850304 -15.73022)
		(width 0.127)
		(layer "F.Cu")
		(net "DRV_ACT_29_35")
	)
	(segment
		(start 172.768006 -13.873226)
		(end 172.768006 -15.349728)
		(width 0.127)
		(layer "F.Cu")
		(net "DRV_ACT_29_35")
	)
	(via
		(at 171.819062 -9.832848)
		(size 0.6096)
		(drill 0.3048)
		(layers "F.Cu" "B.Cu")
		(net "DRV_ACT_29_35")
	)
	(via
		(at 172.768006 -13.873226)
		(size 0.5588)
		(drill 0.3048)
		(layers "F.Cu" "B.Cu")
		(net "DRV_ACT_29_35")
	)
	(segment
		(start 172.72 -10.733786)
		(end 171.819062 -9.832848)
		(width 0.127)
		(layer "B.Cu")
		(net "DRV_ACT_29_35")
	)
	(segment
		(start 167.9194 -6.5278)
		(end 168.514014 -6.5278)
		(width 0.127)
		(layer "B.Cu")
		(net "DRV_ACT_29_35")
	)
	(segment
		(start 172.768006 -13.873226)
		(end 172.72 -13.82522)
		(width 0.127)
		(layer "B.Cu")
		(net "DRV_ACT_29_35")
	)
	(segment
		(start 168.514014 -6.5278)
		(end 171.819062 -9.832848)
		(width 0.127)
		(layer "B.Cu")
		(net "DRV_ACT_29_35")
	)
	(segment
		(start 172.72 -13.82522)
		(end 172.72 -10.733786)
		(width 0.127)
		(layer "B.Cu")
		(net "DRV_ACT_29_35")
	)
	(segment
		(start 140.300456 -14.26972)
		(end 140.300456 -13.242544)
		(width 0.127)
		(layer "F.Cu")
		(net "DRV_ACT_28_34_N")
	)
	(via
		(at 140.300456 -13.242544)
		(size 0.5588)
		(drill 0.3048)
		(layers "F.Cu" "B.Cu")
		(net "DRV_ACT_28_34_N")
	)
	(via
		(at 140.300456 -10.7696)
		(size 0.6096)
		(drill 0.3048)
		(layers "F.Cu" "B.Cu")
		(net "DRV_ACT_28_34_N")
	)
	(segment
		(start 142.0622 -6.6675)
		(end 142.0622 -7.62)
		(width 0.127)
		(layer "B.Cu")
		(net "DRV_ACT_28_34_N")
	)
	(segment
		(start 140.300456 -10.7696)
		(end 140.300456 -13.242544)
		(width 0.127)
		(layer "B.Cu")
		(net "DRV_ACT_28_34_N")
	)
	(segment
		(start 142.0622 -7.62)
		(end 140.300456 -9.381744)
		(width 0.127)
		(layer "B.Cu")
		(net "DRV_ACT_28_34_N")
	)
	(segment
		(start 140.300456 -9.381744)
		(end 140.300456 -10.7696)
		(width 0.127)
		(layer "B.Cu")
		(net "DRV_ACT_28_34_N")
	)
	(segment
		(start 141.222984 -15.42669)
		(end 140.919454 -15.73022)
		(width 0.127)
		(layer "F.Cu")
		(net "DRV_ACT_28_34")
	)
	(segment
		(start 140.919454 -15.73022)
		(end 140.300456 -15.73022)
		(width 0.127)
		(layer "F.Cu")
		(net "DRV_ACT_28_34")
	)
	(segment
		(start 141.222984 -13.819886)
		(end 141.222984 -15.42669)
		(width 0.127)
		(layer "F.Cu")
		(net "DRV_ACT_28_34")
	)
	(via
		(at 141.147292 -9.635236)
		(size 0.6096)
		(drill 0.3048)
		(layers "F.Cu" "B.Cu")
		(net "DRV_ACT_28_34")
	)
	(via
		(at 141.222984 -13.819886)
		(size 0.5588)
		(drill 0.3048)
		(layers "F.Cu" "B.Cu")
		(net "DRV_ACT_28_34")
	)
	(segment
		(start 144.4752 -6.6548)
		(end 143.891 -6.6548)
		(width 0.127)
		(layer "B.Cu")
		(net "DRV_ACT_28_34")
	)
	(segment
		(start 141.222984 -13.819886)
		(end 141.147292 -13.744194)
		(width 0.127)
		(layer "B.Cu")
		(net "DRV_ACT_28_34")
	)
	(segment
		(start 141.147292 -9.398508)
		(end 141.147292 -9.635236)
		(width 0.127)
		(layer "B.Cu")
		(net "DRV_ACT_28_34")
	)
	(segment
		(start 143.891 -6.6548)
		(end 141.147292 -9.398508)
		(width 0.127)
		(layer "B.Cu")
		(net "DRV_ACT_28_34")
	)
	(segment
		(start 141.147292 -13.744194)
		(end 141.147292 -9.635236)
		(width 0.127)
		(layer "B.Cu")
		(net "DRV_ACT_28_34")
	)
	(segment
		(start 108.750354 -14.26972)
		(end 108.750354 -13.246354)
		(width 0.127)
		(layer "F.Cu")
		(net "DRV_ACT_27_33_N")
	)
	(via
		(at 108.750354 -10.7442)
		(size 0.6096)
		(drill 0.3048)
		(layers "F.Cu" "B.Cu")
		(net "DRV_ACT_27_33_N")
	)
	(via
		(at 108.750354 -13.246354)
		(size 0.5588)
		(drill 0.3048)
		(layers "F.Cu" "B.Cu")
		(net "DRV_ACT_27_33_N")
	)
	(segment
		(start 108.750354 -9.2456)
		(end 108.750354 -10.7442)
		(width 0.127)
		(layer "B.Cu")
		(net "DRV_ACT_27_33_N")
	)
	(segment
		(start 110.0074 -7.988554)
		(end 108.750354 -9.2456)
		(width 0.127)
		(layer "B.Cu")
		(net "DRV_ACT_27_33_N")
	)
	(segment
		(start 108.750354 -10.7442)
		(end 108.750354 -13.246354)
		(width 0.127)
		(layer "B.Cu")
		(net "DRV_ACT_27_33_N")
	)
	(segment
		(start 110.0074 -6.8707)
		(end 110.0074 -7.988554)
		(width 0.127)
		(layer "B.Cu")
		(net "DRV_ACT_27_33_N")
	)
	(segment
		(start 109.701076 -13.875258)
		(end 109.701076 -15.147544)
		(width 0.127)
		(layer "F.Cu")
		(net "DRV_ACT_27_33")
	)
	(segment
		(start 109.701076 -15.147544)
		(end 109.1184 -15.73022)
		(width 0.127)
		(layer "F.Cu")
		(net "DRV_ACT_27_33")
	)
	(segment
		(start 109.1184 -15.73022)
		(end 108.750354 -15.73022)
		(width 0.127)
		(layer "F.Cu")
		(net "DRV_ACT_27_33")
	)
	(via
		(at 109.61243 -12.022582)
		(size 0.6096)
		(drill 0.3048)
		(layers "F.Cu" "B.Cu")
		(net "DRV_ACT_27_33")
	)
	(via
		(at 109.701076 -13.875258)
		(size 0.5588)
		(drill 0.3048)
		(layers "F.Cu" "B.Cu")
		(net "DRV_ACT_27_33")
	)
	(segment
		(start 109.61243 -9.56437)
		(end 109.61243 -12.022582)
		(width 0.127)
		(layer "B.Cu")
		(net "DRV_ACT_27_33")
	)
	(segment
		(start 112.395 -6.7818)
		(end 109.61243 -9.56437)
		(width 0.127)
		(layer "B.Cu")
		(net "DRV_ACT_27_33")
	)
	(segment
		(start 109.701076 -13.875258)
		(end 109.61243 -13.786612)
		(width 0.127)
		(layer "B.Cu")
		(net "DRV_ACT_27_33")
	)
	(segment
		(start 109.61243 -13.786612)
		(end 109.61243 -12.022582)
		(width 0.127)
		(layer "B.Cu")
		(net "DRV_ACT_27_33")
	)
	(segment
		(start 77.200506 -13.578078)
		(end 77.200506 -14.26972)
		(width 0.127)
		(layer "F.Cu")
		(net "DRV_ACT_26_32_N")
	)
	(segment
		(start 76.7588 -13.136372)
		(end 77.200506 -13.578078)
		(width 0.127)
		(layer "F.Cu")
		(net "DRV_ACT_26_32_N")
	)
	(via
		(at 76.355702 -11.79576)
		(size 0.6096)
		(drill 0.3048)
		(layers "F.Cu" "B.Cu")
		(net "DRV_ACT_26_32_N")
	)
	(via
		(at 76.7588 -13.136372)
		(size 0.5588)
		(drill 0.3048)
		(layers "F.Cu" "B.Cu")
		(net "DRV_ACT_26_32_N")
	)
	(segment
		(start 64.797178 -7.211314)
		(end 65.423288 -7.837424)
		(width 0.127)
		(layer "B.Cu")
		(net "DRV_ACT_26_32_N")
	)
	(segment
		(start 71.84517 -7.837424)
		(end 75.11796 -11.110214)
		(width 0.127)
		(layer "B.Cu")
		(net "DRV_ACT_26_32_N")
	)
	(segment
		(start 75.11796 -11.110214)
		(end 75.670156 -11.110214)
		(width 0.127)
		(layer "B.Cu")
		(net "DRV_ACT_26_32_N")
	)
	(segment
		(start 76.7588 -13.136372)
		(end 76.7588 -13.133832)
		(width 0.127)
		(layer "B.Cu")
		(net "DRV_ACT_26_32_N")
	)
	(segment
		(start 75.670156 -11.110214)
		(end 76.355702 -11.79576)
		(width 0.127)
		(layer "B.Cu")
		(net "DRV_ACT_26_32_N")
	)
	(segment
		(start 76.355702 -12.730734)
		(end 76.355702 -11.79576)
		(width 0.127)
		(layer "B.Cu")
		(net "DRV_ACT_26_32_N")
	)
	(segment
		(start 64.797178 -6.605016)
		(end 64.797178 -7.211314)
		(width 0.127)
		(layer "B.Cu")
		(net "DRV_ACT_26_32_N")
	)
	(segment
		(start 65.423288 -7.837424)
		(end 71.84517 -7.837424)
		(width 0.127)
		(layer "B.Cu")
		(net "DRV_ACT_26_32_N")
	)
	(segment
		(start 76.7588 -13.133832)
		(end 76.355702 -12.730734)
		(width 0.127)
		(layer "B.Cu")
		(net "DRV_ACT_26_32_N")
	)
	(segment
		(start 78.130146 -13.859256)
		(end 78.130146 -15.03934)
		(width 0.127)
		(layer "F.Cu")
		(net "DRV_ACT_26_32")
	)
	(segment
		(start 77.439266 -15.73022)
		(end 77.200506 -15.73022)
		(width 0.127)
		(layer "F.Cu")
		(net "DRV_ACT_26_32")
	)
	(segment
		(start 78.130146 -15.03934)
		(end 77.439266 -15.73022)
		(width 0.127)
		(layer "F.Cu")
		(net "DRV_ACT_26_32")
	)
	(via
		(at 78.130146 -13.859256)
		(size 0.5588)
		(drill 0.3048)
		(layers "F.Cu" "B.Cu")
		(net "DRV_ACT_26_32")
	)
	(via
		(at 77.768196 -11.23569)
		(size 0.6096)
		(drill 0.3048)
		(layers "F.Cu" "B.Cu")
		(net "DRV_ACT_26_32")
	)
	(segment
		(start 71.838566 -6.82498)
		(end 74.950066 -9.93648)
		(width 0.127)
		(layer "B.Cu")
		(net "DRV_ACT_26_32")
	)
	(segment
		(start 76.44765 -9.93648)
		(end 77.74686 -11.23569)
		(width 0.127)
		(layer "B.Cu")
		(net "DRV_ACT_26_32")
	)
	(segment
		(start 78.130146 -11.59764)
		(end 77.768196 -11.23569)
		(width 0.127)
		(layer "B.Cu")
		(net "DRV_ACT_26_32")
	)
	(segment
		(start 77.74686 -11.23569)
		(end 77.768196 -11.23569)
		(width 0.127)
		(layer "B.Cu")
		(net "DRV_ACT_26_32")
	)
	(segment
		(start 74.950066 -9.93648)
		(end 76.44765 -9.93648)
		(width 0.127)
		(layer "B.Cu")
		(net "DRV_ACT_26_32")
	)
	(segment
		(start 70.757796 -6.82498)
		(end 71.838566 -6.82498)
		(width 0.127)
		(layer "B.Cu")
		(net "DRV_ACT_26_32")
	)
	(segment
		(start 78.130146 -13.859256)
		(end 78.130146 -11.59764)
		(width 0.127)
		(layer "B.Cu")
		(net "DRV_ACT_26_32")
	)
	(segment
		(start 44.207684 -11.240262)
		(end 45.645832 -12.67841)
		(width 0.127)
		(layer "F.Cu")
		(net "DRV_ACT_25_31_N")
	)
	(segment
		(start 44.207684 -11.021568)
		(end 44.207684 -11.240262)
		(width 0.127)
		(layer "F.Cu")
		(net "DRV_ACT_25_31_N")
	)
	(segment
		(start 32.030924 -7.618984)
		(end 32.573722 -8.161782)
		(width 0.127)
		(layer "F.Cu")
		(net "DRV_ACT_25_31_N")
	)
	(segment
		(start 32.573722 -8.161782)
		(end 41.347898 -8.161782)
		(width 0.127)
		(layer "F.Cu")
		(net "DRV_ACT_25_31_N")
	)
	(segment
		(start 45.650404 -14.26972)
		(end 45.650404 -12.682982)
		(width 0.127)
		(layer "F.Cu")
		(net "DRV_ACT_25_31_N")
	)
	(segment
		(start 45.650404 -12.682982)
		(end 45.645832 -12.67841)
		(width 0.127)
		(layer "F.Cu")
		(net "DRV_ACT_25_31_N")
	)
	(segment
		(start 41.347898 -8.161782)
		(end 44.207684 -11.021568)
		(width 0.127)
		(layer "F.Cu")
		(net "DRV_ACT_25_31_N")
	)
	(via
		(at 32.030924 -7.618984)
		(size 0.5588)
		(drill 0.3048)
		(layers "F.Cu" "B.Cu")
		(net "DRV_ACT_25_31_N")
	)
	(via
		(at 45.645832 -12.67841)
		(size 0.6604)
		(drill 0.3302)
		(layers "F.Cu" "B.Cu")
		(net "DRV_ACT_25_31_N")
	)
	(segment
		(start 32.0294 -6.0071)
		(end 32.0294 -7.1628)
		(width 0.127)
		(layer "B.Cu")
		(net "DRV_ACT_25_31_N")
	)
	(segment
		(start 32.030924 -7.164324)
		(end 32.030924 -7.618984)
		(width 0.127)
		(layer "B.Cu")
		(net "DRV_ACT_25_31_N")
	)
	(segment
		(start 32.0294 -7.1628)
		(end 32.030924 -7.164324)
		(width 0.127)
		(layer "B.Cu")
		(net "DRV_ACT_25_31_N")
	)
	(segment
		(start 34.426906 -7.62381)
		(end 41.388284 -7.62381)
		(width 0.127)
		(layer "F.Cu")
		(net "DRV_ACT_25_31")
	)
	(segment
		(start 45.650404 -15.73022)
		(end 46.143672 -15.73022)
		(width 0.127)
		(layer "F.Cu")
		(net "DRV_ACT_25_31")
	)
	(segment
		(start 46.440852 -15.43304)
		(end 46.440852 -12.676378)
		(width 0.127)
		(layer "F.Cu")
		(net "DRV_ACT_25_31")
	)
	(segment
		(start 46.440852 -12.676378)
		(end 44.91609 -11.151616)
		(width 0.127)
		(layer "F.Cu")
		(net "DRV_ACT_25_31")
	)
	(segment
		(start 46.143672 -15.73022)
		(end 46.440852 -15.43304)
		(width 0.127)
		(layer "F.Cu")
		(net "DRV_ACT_25_31")
	)
	(segment
		(start 34.417 -7.613904)
		(end 34.426906 -7.62381)
		(width 0.127)
		(layer "F.Cu")
		(net "DRV_ACT_25_31")
	)
	(segment
		(start 41.388284 -7.62381)
		(end 44.91609 -11.151616)
		(width 0.127)
		(layer "F.Cu")
		(net "DRV_ACT_25_31")
	)
	(via
		(at 34.417 -7.613904)
		(size 0.5588)
		(drill 0.3048)
		(layers "F.Cu" "B.Cu")
		(net "DRV_ACT_25_31")
	)
	(via
		(at 44.91609 -11.151616)
		(size 0.6604)
		(drill 0.3302)
		(layers "F.Cu" "B.Cu")
		(net "DRV_ACT_25_31")
	)
	(segment
		(start 34.417 -6.35)
		(end 34.417 -7.613904)
		(width 0.127)
		(layer "B.Cu")
		(net "DRV_ACT_25_31")
	)
	(segment
		(start 14.100302 -14.26972)
		(end 14.100302 -13.084302)
		(width 0.127)
		(layer "F.Cu")
		(net "DRV_ACT_24_30_N")
	)
	(via
		(at 14.100302 -13.084302)
		(size 0.5588)
		(drill 0.3048)
		(layers "F.Cu" "B.Cu")
		(net "DRV_ACT_24_30_N")
	)
	(via
		(at 14.857476 -10.27811)
		(size 0.6096)
		(drill 0.3048)
		(layers "F.Cu" "B.Cu")
		(net "DRV_ACT_24_30_N")
	)
	(segment
		(start 17.896586 -7.239)
		(end 14.857476 -10.27811)
		(width 0.127)
		(layer "B.Cu")
		(net "DRV_ACT_24_30_N")
	)
	(segment
		(start 19.2786 -7.239)
		(end 17.896586 -7.239)
		(width 0.127)
		(layer "B.Cu")
		(net "DRV_ACT_24_30_N")
	)
	(segment
		(start 22.3012 -6.3627)
		(end 20.1549 -6.3627)
		(width 0.127)
		(layer "B.Cu")
		(net "DRV_ACT_24_30_N")
	)
	(segment
		(start 14.100302 -11.035284)
		(end 14.857476 -10.27811)
		(width 0.127)
		(layer "B.Cu")
		(net "DRV_ACT_24_30_N")
	)
	(segment
		(start 20.1549 -6.3627)
		(end 19.2786 -7.239)
		(width 0.127)
		(layer "B.Cu")
		(net "DRV_ACT_24_30_N")
	)
	(segment
		(start 14.100302 -13.084302)
		(end 14.100302 -11.035284)
		(width 0.127)
		(layer "B.Cu")
		(net "DRV_ACT_24_30_N")
	)
	(segment
		(start 15.0114 -14.2748)
		(end 15.0114 -15.2654)
		(width 0.127)
		(layer "F.Cu")
		(net "DRV_ACT_24_30")
	)
	(segment
		(start 14.54658 -15.73022)
		(end 14.100302 -15.73022)
		(width 0.127)
		(layer "F.Cu")
		(net "DRV_ACT_24_30")
	)
	(segment
		(start 15.0114 -15.2654)
		(end 14.54658 -15.73022)
		(width 0.127)
		(layer "F.Cu")
		(net "DRV_ACT_24_30")
	)
	(via
		(at 14.986 -12.1412)
		(size 0.6096)
		(drill 0.3048)
		(layers "F.Cu" "B.Cu")
		(net "DRV_ACT_24_30")
	)
	(via
		(at 15.0114 -14.2748)
		(size 0.5588)
		(drill 0.3048)
		(layers "F.Cu" "B.Cu")
		(net "DRV_ACT_24_30")
	)
	(segment
		(start 15.0114 -14.2748)
		(end 14.986 -14.2494)
		(width 0.127)
		(layer "B.Cu")
		(net "DRV_ACT_24_30")
	)
	(segment
		(start 18.146776 -7.752842)
		(end 14.986 -10.913618)
		(width 0.127)
		(layer "B.Cu")
		(net "DRV_ACT_24_30")
	)
	(segment
		(start 24.6888 -6.7056)
		(end 23.641558 -7.752842)
		(width 0.127)
		(layer "B.Cu")
		(net "DRV_ACT_24_30")
	)
	(segment
		(start 23.641558 -7.752842)
		(end 18.146776 -7.752842)
		(width 0.127)
		(layer "B.Cu")
		(net "DRV_ACT_24_30")
	)
	(segment
		(start 14.986 -10.913618)
		(end 14.986 -12.1412)
		(width 0.127)
		(layer "B.Cu")
		(net "DRV_ACT_24_30")
	)
	(segment
		(start 14.986 -14.2494)
		(end 14.986 -12.1412)
		(width 0.127)
		(layer "B.Cu")
		(net "DRV_ACT_24_30")
	)
	(via
		(at 162.047174 -2.112264)
		(size 0.6096)
		(drill 0.3048)
		(layers "F.Cu" "B.Cu")
		(net "DRIVE_A_29_35_FLT_LED")
	)
	(segment
		(start 162.5727 -3.5687)
		(end 162.5727 -3.1242)
		(width 0.127)
		(layer "B.Cu")
		(net "DRIVE_A_29_35_FLT_LED")
	)
	(segment
		(start 54.119272 -0.185928)
		(end 49.650142 -4.655058)
		(width 0.127)
		(layer "B.Cu")
		(net "DRIVE_A_29_35_FLT_LED")
	)
	(segment
		(start 49.650142 -4.655058)
		(end 49.650142 -8.849868)
		(width 0.127)
		(layer "B.Cu")
		(net "DRIVE_A_29_35_FLT_LED")
	)
	(segment
		(start 161.098738 -1.163828)
		(end 141.597126 -1.163828)
		(width 0.127)
		(layer "B.Cu")
		(net "DRIVE_A_29_35_FLT_LED")
	)
	(segment
		(start 162.047174 -2.112264)
		(end 161.098738 -1.163828)
		(width 0.127)
		(layer "B.Cu")
		(net "DRIVE_A_29_35_FLT_LED")
	)
	(segment
		(start 162.90925 -3.90525)
		(end 162.5727 -3.5687)
		(width 0.127)
		(layer "B.Cu")
		(net "DRIVE_A_29_35_FLT_LED")
	)
	(segment
		(start 162.90925 -4.6355)
		(end 162.90925 -3.90525)
		(width 0.127)
		(layer "B.Cu")
		(net "DRIVE_A_29_35_FLT_LED")
	)
	(segment
		(start 162.5727 -2.63779)
		(end 162.047174 -2.112264)
		(width 0.127)
		(layer "B.Cu")
		(net "DRIVE_A_29_35_FLT_LED")
	)
	(segment
		(start 140.619226 -0.185928)
		(end 54.119272 -0.185928)
		(width 0.127)
		(layer "B.Cu")
		(net "DRIVE_A_29_35_FLT_LED")
	)
	(segment
		(start 141.597126 -1.163828)
		(end 140.619226 -0.185928)
		(width 0.127)
		(layer "B.Cu")
		(net "DRIVE_A_29_35_FLT_LED")
	)
	(segment
		(start 162.5727 -3.1242)
		(end 162.5727 -2.63779)
		(width 0.127)
		(layer "B.Cu")
		(net "DRIVE_A_29_35_FLT_LED")
	)
	(via
		(at 166.01948 -2.136648)
		(size 0.6096)
		(drill 0.3048)
		(layers "F.Cu" "B.Cu")
		(net "DRIVE_A_29_35_ACT")
	)
	(segment
		(start 53.687472 0.169672)
		(end 140.810234 0.169672)
		(width 0.127)
		(layer "B.Cu")
		(net "DRIVE_A_29_35_ACT")
	)
	(segment
		(start 166.4081 -3.77825)
		(end 166.51605 -3.8862)
		(width 0.127)
		(layer "B.Cu")
		(net "DRIVE_A_29_35_ACT")
	)
	(segment
		(start 140.810234 0.169672)
		(end 141.782292 -0.802386)
		(width 0.127)
		(layer "B.Cu")
		(net "DRIVE_A_29_35_ACT")
	)
	(segment
		(start 48.64989 -8.849868)
		(end 48.64989 -4.86791)
		(width 0.127)
		(layer "B.Cu")
		(net "DRIVE_A_29_35_ACT")
	)
	(segment
		(start 166.01948 -2.136648)
		(end 166.4081 -2.525268)
		(width 0.127)
		(layer "B.Cu")
		(net "DRIVE_A_29_35_ACT")
	)
	(segment
		(start 164.685218 -0.802386)
		(end 166.01948 -2.136648)
		(width 0.127)
		(layer "B.Cu")
		(net "DRIVE_A_29_35_ACT")
	)
	(segment
		(start 166.51605 -3.8862)
		(end 166.51605 -4.6355)
		(width 0.127)
		(layer "B.Cu")
		(net "DRIVE_A_29_35_ACT")
	)
	(segment
		(start 166.4081 -2.525268)
		(end 166.4081 -3.175)
		(width 0.127)
		(layer "B.Cu")
		(net "DRIVE_A_29_35_ACT")
	)
	(segment
		(start 48.64989 -4.86791)
		(end 53.687472 0.169672)
		(width 0.127)
		(layer "B.Cu")
		(net "DRIVE_A_29_35_ACT")
	)
	(segment
		(start 141.782292 -0.802386)
		(end 164.685218 -0.802386)
		(width 0.127)
		(layer "B.Cu")
		(net "DRIVE_A_29_35_ACT")
	)
	(segment
		(start 166.4081 -3.175)
		(end 166.4081 -3.77825)
		(width 0.127)
		(layer "B.Cu")
		(net "DRIVE_A_29_35_ACT")
	)
	(via
		(at 139.0142 -2.286)
		(size 0.6096)
		(drill 0.3048)
		(layers "F.Cu" "B.Cu")
		(net "DRIVE_A_28_34_FLT_LED")
	)
	(segment
		(start 137.625328 -0.897128)
		(end 139.0142 -2.286)
		(width 0.127)
		(layer "B.Cu")
		(net "DRIVE_A_28_34_FLT_LED")
	)
	(segment
		(start 139.2555 -3.302)
		(end 139.2555 -2.5273)
		(width 0.127)
		(layer "B.Cu")
		(net "DRIVE_A_28_34_FLT_LED")
	)
	(segment
		(start 51.650138 -5.576062)
		(end 51.64836 -5.574284)
		(width 0.127)
		(layer "B.Cu")
		(net "DRIVE_A_28_34_FLT_LED")
	)
	(segment
		(start 51.64836 -4.843272)
		(end 55.594504 -0.897128)
		(width 0.127)
		(layer "B.Cu")
		(net "DRIVE_A_28_34_FLT_LED")
	)
	(segment
		(start 139.43965 -4.7625)
		(end 139.43965 -3.48615)
		(width 0.127)
		(layer "B.Cu")
		(net "DRIVE_A_28_34_FLT_LED")
	)
	(segment
		(start 139.2555 -2.5273)
		(end 139.0142 -2.286)
		(width 0.127)
		(layer "B.Cu")
		(net "DRIVE_A_28_34_FLT_LED")
	)
	(segment
		(start 139.43965 -3.48615)
		(end 139.2555 -3.302)
		(width 0.127)
		(layer "B.Cu")
		(net "DRIVE_A_28_34_FLT_LED")
	)
	(segment
		(start 51.650138 -8.849868)
		(end 51.650138 -5.576062)
		(width 0.127)
		(layer "B.Cu")
		(net "DRIVE_A_28_34_FLT_LED")
	)
	(segment
		(start 51.64836 -5.574284)
		(end 51.64836 -4.843272)
		(width 0.127)
		(layer "B.Cu")
		(net "DRIVE_A_28_34_FLT_LED")
	)
	(segment
		(start 55.594504 -0.897128)
		(end 137.625328 -0.897128)
		(width 0.127)
		(layer "B.Cu")
		(net "DRIVE_A_28_34_FLT_LED")
	)
	(via
		(at 142.1892 -2.2606)
		(size 0.6096)
		(drill 0.3048)
		(layers "F.Cu" "B.Cu")
		(net "DRIVE_A_28_34_ACT")
	)
	(segment
		(start 143.04645 -3.66395)
		(end 142.6845 -3.302)
		(width 0.127)
		(layer "B.Cu")
		(net "DRIVE_A_28_34_ACT")
	)
	(segment
		(start 50.65014 -4.77266)
		(end 54.881272 -0.541528)
		(width 0.127)
		(layer "B.Cu")
		(net "DRIVE_A_28_34_ACT")
	)
	(segment
		(start 143.04645 -4.7625)
		(end 143.04645 -3.66395)
		(width 0.127)
		(layer "B.Cu")
		(net "DRIVE_A_28_34_ACT")
	)
	(segment
		(start 50.65014 -8.849868)
		(end 50.65014 -4.77266)
		(width 0.127)
		(layer "B.Cu")
		(net "DRIVE_A_28_34_ACT")
	)
	(segment
		(start 142.6845 -2.7559)
		(end 142.1892 -2.2606)
		(width 0.127)
		(layer "B.Cu")
		(net "DRIVE_A_28_34_ACT")
	)
	(segment
		(start 142.6845 -3.302)
		(end 142.6845 -2.7559)
		(width 0.127)
		(layer "B.Cu")
		(net "DRIVE_A_28_34_ACT")
	)
	(segment
		(start 140.470128 -0.541528)
		(end 142.1892 -2.2606)
		(width 0.127)
		(layer "B.Cu")
		(net "DRIVE_A_28_34_ACT")
	)
	(segment
		(start 54.881272 -0.541528)
		(end 140.470128 -0.541528)
		(width 0.127)
		(layer "B.Cu")
		(net "DRIVE_A_28_34_ACT")
	)
	(via
		(at 106.8324 -2.4638)
		(size 0.6096)
		(drill 0.3048)
		(layers "F.Cu" "B.Cu")
		(net "DRIVE_A_27_33_FLT_LED")
	)
	(segment
		(start 107.38485 -3.81635)
		(end 107.0737 -3.5052)
		(width 0.127)
		(layer "B.Cu")
		(net "DRIVE_A_27_33_FLT_LED")
	)
	(segment
		(start 107.0737 -3.5052)
		(end 107.0737 -2.7051)
		(width 0.127)
		(layer "B.Cu")
		(net "DRIVE_A_27_33_FLT_LED")
	)
	(segment
		(start 53.650134 -8.849868)
		(end 53.650134 -4.671314)
		(width 0.127)
		(layer "B.Cu")
		(net "DRIVE_A_27_33_FLT_LED")
	)
	(segment
		(start 53.650134 -4.671314)
		(end 56.71312 -1.608328)
		(width 0.127)
		(layer "B.Cu")
		(net "DRIVE_A_27_33_FLT_LED")
	)
	(segment
		(start 56.71312 -1.608328)
		(end 105.976928 -1.608328)
		(width 0.127)
		(layer "B.Cu")
		(net "DRIVE_A_27_33_FLT_LED")
	)
	(segment
		(start 105.976928 -1.608328)
		(end 106.8324 -2.4638)
		(width 0.127)
		(layer "B.Cu")
		(net "DRIVE_A_27_33_FLT_LED")
	)
	(segment
		(start 107.38485 -4.9657)
		(end 107.38485 -3.81635)
		(width 0.127)
		(layer "B.Cu")
		(net "DRIVE_A_27_33_FLT_LED")
	)
	(segment
		(start 107.0737 -2.7051)
		(end 106.8324 -2.4638)
		(width 0.127)
		(layer "B.Cu")
		(net "DRIVE_A_27_33_FLT_LED")
	)
	(via
		(at 110.5408 -2.4384)
		(size 0.6096)
		(drill 0.3048)
		(layers "F.Cu" "B.Cu")
		(net "DRIVE_A_27_33_ACT")
	)
	(segment
		(start 52.650136 -8.849868)
		(end 52.650136 -4.642104)
		(width 0.127)
		(layer "B.Cu")
		(net "DRIVE_A_27_33_ACT")
	)
	(segment
		(start 110.99165 -4.9657)
		(end 110.99165 -3.84175)
		(width 0.127)
		(layer "B.Cu")
		(net "DRIVE_A_27_33_ACT")
	)
	(segment
		(start 56.039512 -1.252728)
		(end 109.355128 -1.252728)
		(width 0.127)
		(layer "B.Cu")
		(net "DRIVE_A_27_33_ACT")
	)
	(segment
		(start 52.650136 -4.642104)
		(end 56.039512 -1.252728)
		(width 0.127)
		(layer "B.Cu")
		(net "DRIVE_A_27_33_ACT")
	)
	(segment
		(start 110.6551 -3.5052)
		(end 110.6551 -2.5527)
		(width 0.127)
		(layer "B.Cu")
		(net "DRIVE_A_27_33_ACT")
	)
	(segment
		(start 110.6551 -2.5527)
		(end 110.5408 -2.4384)
		(width 0.127)
		(layer "B.Cu")
		(net "DRIVE_A_27_33_ACT")
	)
	(segment
		(start 110.99165 -3.84175)
		(end 110.6551 -3.5052)
		(width 0.127)
		(layer "B.Cu")
		(net "DRIVE_A_27_33_ACT")
	)
	(segment
		(start 109.355128 -1.252728)
		(end 110.5408 -2.4384)
		(width 0.127)
		(layer "B.Cu")
		(net "DRIVE_A_27_33_ACT")
	)
	(via
		(at 68.707 -2.2606)
		(size 0.6096)
		(drill 0.3048)
		(layers "F.Cu" "B.Cu")
		(net "DRIVE_A_26_32_FLT_LED")
	)
	(segment
		(start 53.650134 -14.949932)
		(end 54.160928 -14.439138)
		(width 0.127)
		(layer "B.Cu")
		(net "DRIVE_A_26_32_FLT_LED")
	)
	(segment
		(start 68.43903 -1.99263)
		(end 68.707 -2.2606)
		(width 0.127)
		(layer "B.Cu")
		(net "DRIVE_A_26_32_FLT_LED")
	)
	(segment
		(start 57.177686 -1.99263)
		(end 68.43903 -1.99263)
		(width 0.127)
		(layer "B.Cu")
		(net "DRIVE_A_26_32_FLT_LED")
	)
	(segment
		(start 69.080888 -2.634488)
		(end 69.080888 -3.247644)
		(width 0.127)
		(layer "B.Cu")
		(net "DRIVE_A_26_32_FLT_LED")
	)
	(segment
		(start 69.362828 -3.529584)
		(end 69.080888 -3.247644)
		(width 0.127)
		(layer "B.Cu")
		(net "DRIVE_A_26_32_FLT_LED")
	)
	(segment
		(start 54.160928 -5.009388)
		(end 57.177686 -1.99263)
		(width 0.127)
		(layer "B.Cu")
		(net "DRIVE_A_26_32_FLT_LED")
	)
	(segment
		(start 54.160928 -14.439138)
		(end 54.160928 -5.009388)
		(width 0.127)
		(layer "B.Cu")
		(net "DRIVE_A_26_32_FLT_LED")
	)
	(segment
		(start 68.707 -2.2606)
		(end 69.080888 -2.634488)
		(width 0.127)
		(layer "B.Cu")
		(net "DRIVE_A_26_32_FLT_LED")
	)
	(segment
		(start 69.362828 -4.700016)
		(end 69.362828 -3.529584)
		(width 0.127)
		(layer "B.Cu")
		(net "DRIVE_A_26_32_FLT_LED")
	)
	(via
		(at 66.1924 -3.302)
		(size 0.6096)
		(drill 0.3048)
		(layers "F.Cu" "B.Cu")
		(net "DRIVE_A_26_32_ACT")
	)
	(via
		(at 57.9374 -2.8194)
		(size 0.6096)
		(drill 0.3048)
		(layers "F.Cu" "B.Cu")
		(net "DRIVE_A_26_32_ACT")
	)
	(segment
		(start 54.519576 -15.493746)
		(end 53.94071 -16.072612)
		(width 0.127)
		(layer "B.Cu")
		(net "DRIVE_A_26_32_ACT")
	)
	(segment
		(start 53.94071 -16.072612)
		(end 52.813458 -16.072612)
		(width 0.127)
		(layer "B.Cu")
		(net "DRIVE_A_26_32_ACT")
	)
	(segment
		(start 58.40857 -2.34823)
		(end 57.9374 -2.8194)
		(width 0.127)
		(layer "B.Cu")
		(net "DRIVE_A_26_32_ACT")
	)
	(segment
		(start 65.141094 -2.542286)
		(end 64.947038 -2.34823)
		(width 0.127)
		(layer "B.Cu")
		(net "DRIVE_A_26_32_ACT")
	)
	(segment
		(start 57.531762 -2.8194)
		(end 54.519576 -5.831586)
		(width 0.127)
		(layer "B.Cu")
		(net "DRIVE_A_26_32_ACT")
	)
	(segment
		(start 66.2686 -4.212844)
		(end 65.781428 -4.700016)
		(width 0.127)
		(layer "B.Cu")
		(net "DRIVE_A_26_32_ACT")
	)
	(segment
		(start 54.519576 -5.831586)
		(end 54.519576 -15.493746)
		(width 0.127)
		(layer "B.Cu")
		(net "DRIVE_A_26_32_ACT")
	)
	(segment
		(start 57.9374 -2.8194)
		(end 57.531762 -2.8194)
		(width 0.127)
		(layer "B.Cu")
		(net "DRIVE_A_26_32_ACT")
	)
	(segment
		(start 65.141094 -3.24358)
		(end 66.13398 -3.24358)
		(width 0.127)
		(layer "B.Cu")
		(net "DRIVE_A_26_32_ACT")
	)
	(segment
		(start 66.1924 -3.302)
		(end 66.2686 -3.3782)
		(width 0.127)
		(layer "B.Cu")
		(net "DRIVE_A_26_32_ACT")
	)
	(segment
		(start 65.141094 -3.24358)
		(end 65.141094 -2.542286)
		(width 0.127)
		(layer "B.Cu")
		(net "DRIVE_A_26_32_ACT")
	)
	(segment
		(start 66.2686 -3.3782)
		(end 66.2686 -4.212844)
		(width 0.127)
		(layer "B.Cu")
		(net "DRIVE_A_26_32_ACT")
	)
	(segment
		(start 52.650136 -15.90929)
		(end 52.650136 -14.949932)
		(width 0.127)
		(layer "B.Cu")
		(net "DRIVE_A_26_32_ACT")
	)
	(segment
		(start 64.947038 -2.34823)
		(end 58.40857 -2.34823)
		(width 0.127)
		(layer "B.Cu")
		(net "DRIVE_A_26_32_ACT")
	)
	(segment
		(start 52.813458 -16.072612)
		(end 52.650136 -15.90929)
		(width 0.127)
		(layer "B.Cu")
		(net "DRIVE_A_26_32_ACT")
	)
	(segment
		(start 66.13398 -3.24358)
		(end 66.1924 -3.302)
		(width 0.127)
		(layer "B.Cu")
		(net "DRIVE_A_26_32_ACT")
	)
	(via
		(at 31.1912 -2.2352)
		(size 0.6096)
		(drill 0.3048)
		(layers "F.Cu" "B.Cu")
		(net "DRIVE_A_25_31_FLT_LED")
	)
	(segment
		(start 45.649896 -5.492496)
		(end 42.037 -1.8796)
		(width 0.127)
		(layer "B.Cu")
		(net "DRIVE_A_25_31_FLT_LED")
	)
	(segment
		(start 31.5468 -1.8796)
		(end 31.1912 -2.2352)
		(width 0.127)
		(layer "B.Cu")
		(net "DRIVE_A_25_31_FLT_LED")
	)
	(segment
		(start 30.0863 -3.44805)
		(end 29.43225 -4.1021)
		(width 0.127)
		(layer "B.Cu")
		(net "DRIVE_A_25_31_FLT_LED")
	)
	(segment
		(start 30.0863 -2.6416)
		(end 30.0863 -3.44805)
		(width 0.127)
		(layer "B.Cu")
		(net "DRIVE_A_25_31_FLT_LED")
	)
	(segment
		(start 30.7848 -2.6416)
		(end 31.1912 -2.2352)
		(width 0.127)
		(layer "B.Cu")
		(net "DRIVE_A_25_31_FLT_LED")
	)
	(segment
		(start 42.037 -1.8796)
		(end 31.5468 -1.8796)
		(width 0.127)
		(layer "B.Cu")
		(net "DRIVE_A_25_31_FLT_LED")
	)
	(segment
		(start 45.649896 -8.849868)
		(end 45.649896 -5.492496)
		(width 0.127)
		(layer "B.Cu")
		(net "DRIVE_A_25_31_FLT_LED")
	)
	(segment
		(start 30.0863 -2.6416)
		(end 30.7848 -2.6416)
		(width 0.127)
		(layer "B.Cu")
		(net "DRIVE_A_25_31_FLT_LED")
	)
	(via
		(at 34.3662 -2.413)
		(size 0.6096)
		(drill 0.3048)
		(layers "F.Cu" "B.Cu")
		(net "DRIVE_A_25_31_ACT")
	)
	(segment
		(start 33.01365 -3.06451)
		(end 33.147 -2.93116)
		(width 0.127)
		(layer "B.Cu")
		(net "DRIVE_A_25_31_ACT")
	)
	(segment
		(start 33.147 -2.8321)
		(end 33.3375 -2.6416)
		(width 0.127)
		(layer "B.Cu")
		(net "DRIVE_A_25_31_ACT")
	)
	(segment
		(start 33.147 -2.93116)
		(end 33.147 -2.8321)
		(width 0.127)
		(layer "B.Cu")
		(net "DRIVE_A_25_31_ACT")
	)
	(segment
		(start 44.649898 -5.508498)
		(end 44.649898 -8.849868)
		(width 0.127)
		(layer "B.Cu")
		(net "DRIVE_A_25_31_ACT")
	)
	(segment
		(start 33.3375 -2.6416)
		(end 33.5661 -2.413)
		(width 0.127)
		(layer "B.Cu")
		(net "DRIVE_A_25_31_ACT")
	)
	(segment
		(start 33.01365 -4.1021)
		(end 33.01365 -3.06451)
		(width 0.127)
		(layer "B.Cu")
		(net "DRIVE_A_25_31_ACT")
	)
	(segment
		(start 33.5661 -2.413)
		(end 34.3662 -2.413)
		(width 0.127)
		(layer "B.Cu")
		(net "DRIVE_A_25_31_ACT")
	)
	(segment
		(start 41.5544 -2.413)
		(end 44.649898 -5.508498)
		(width 0.127)
		(layer "B.Cu")
		(net "DRIVE_A_25_31_ACT")
	)
	(segment
		(start 34.3662 -2.413)
		(end 41.5544 -2.413)
		(width 0.127)
		(layer "B.Cu")
		(net "DRIVE_A_25_31_ACT")
	)
	(via
		(at 20.828 -2.286)
		(size 0.6096)
		(drill 0.3048)
		(layers "F.Cu" "B.Cu")
		(net "DRIVE_A_24_30_FLT_LED")
	)
	(segment
		(start 42.973752 -0.8382)
		(end 24.26208 -0.8382)
		(width 0.127)
		(layer "B.Cu")
		(net "DRIVE_A_24_30_FLT_LED")
	)
	(segment
		(start 20.828 -2.286)
		(end 20.701 -2.413)
		(width 0.127)
		(layer "B.Cu")
		(net "DRIVE_A_24_30_FLT_LED")
	)
	(segment
		(start 22.96668 -2.1336)
		(end 20.9804 -2.1336)
		(width 0.127)
		(layer "B.Cu")
		(net "DRIVE_A_24_30_FLT_LED")
	)
	(segment
		(start 20.9804 -2.1336)
		(end 20.828 -2.286)
		(width 0.127)
		(layer "B.Cu")
		(net "DRIVE_A_24_30_FLT_LED")
	)
	(segment
		(start 19.70405 -2.99085)
		(end 19.7993 -2.8956)
		(width 0.127)
		(layer "B.Cu")
		(net "DRIVE_A_24_30_FLT_LED")
	)
	(segment
		(start 47.649892 -8.849868)
		(end 47.649892 -5.51434)
		(width 0.127)
		(layer "B.Cu")
		(net "DRIVE_A_24_30_FLT_LED")
	)
	(segment
		(start 20.2819 -2.413)
		(end 19.7993 -2.8956)
		(width 0.127)
		(layer "B.Cu")
		(net "DRIVE_A_24_30_FLT_LED")
	)
	(segment
		(start 24.26208 -0.8382)
		(end 22.96668 -2.1336)
		(width 0.127)
		(layer "B.Cu")
		(net "DRIVE_A_24_30_FLT_LED")
	)
	(segment
		(start 47.649892 -5.51434)
		(end 42.973752 -0.8382)
		(width 0.127)
		(layer "B.Cu")
		(net "DRIVE_A_24_30_FLT_LED")
	)
	(segment
		(start 20.701 -2.413)
		(end 20.2819 -2.413)
		(width 0.127)
		(layer "B.Cu")
		(net "DRIVE_A_24_30_FLT_LED")
	)
	(segment
		(start 19.70405 -4.4577)
		(end 19.70405 -2.99085)
		(width 0.127)
		(layer "B.Cu")
		(net "DRIVE_A_24_30_FLT_LED")
	)
	(via
		(at 24.384 -2.667)
		(size 0.6096)
		(drill 0.3048)
		(layers "F.Cu" "B.Cu")
		(net "DRIVE_A_24_30_ACT")
	)
	(segment
		(start 23.6601 -2.667)
		(end 23.3299 -2.9972)
		(width 0.127)
		(layer "B.Cu")
		(net "DRIVE_A_24_30_ACT")
	)
	(segment
		(start 23.28545 -3.04165)
		(end 23.3299 -2.9972)
		(width 0.127)
		(layer "B.Cu")
		(net "DRIVE_A_24_30_ACT")
	)
	(segment
		(start 46.649894 -5.451094)
		(end 42.545 -1.3462)
		(width 0.127)
		(layer "B.Cu")
		(net "DRIVE_A_24_30_ACT")
	)
	(segment
		(start 46.649894 -8.849868)
		(end 46.649894 -5.451094)
		(width 0.127)
		(layer "B.Cu")
		(net "DRIVE_A_24_30_ACT")
	)
	(segment
		(start 24.384 -2.667)
		(end 23.6601 -2.667)
		(width 0.127)
		(layer "B.Cu")
		(net "DRIVE_A_24_30_ACT")
	)
	(segment
		(start 25.7048 -1.3462)
		(end 24.384 -2.667)
		(width 0.127)
		(layer "B.Cu")
		(net "DRIVE_A_24_30_ACT")
	)
	(segment
		(start 23.28545 -4.4577)
		(end 23.28545 -3.04165)
		(width 0.127)
		(layer "B.Cu")
		(net "DRIVE_A_24_30_ACT")
	)
	(segment
		(start 42.545 -1.3462)
		(end 25.7048 -1.3462)
		(width 0.127)
		(layer "B.Cu")
		(net "DRIVE_A_24_30_ACT")
	)
	(zone
		(layer "F.Cu")
		(hatch none 0.5)
		(connect_pads
			(clearance 0)
		)
		(min_thickness 0.25)
		(keepout
			(tracks allowed)
			(vias allowed)
			(pads allowed)
			(copperpour allowed)
			(footprints not_allowed)
		)
		(placement
			(enabled no)
			(sheetname "")
		)
		(fill
			(thermal_gap 0.5)
			(thermal_bridge_width 0.5)
			(island_removal_mode 0)
		)
		(polygon
			(pts
				(arc
					(start 174.325026 -4.99999)
					(mid 172.875194 -6.449822)
					(end 171.425108 -4.99999)
				)
				(arc
					(start 171.425108 -4.99999)
					(mid 172.875194 -3.549904)
					(end 174.325026 -4.99999)
				)
			)
		)
	)
	(zone
		(net "GND")
		(layer "F.Cu")
		(hatch none 0.5)
		(connect_pads
			(clearance 0.5)
		)
		(min_thickness 0.25)
		(fill yes
			(thermal_gap 0.5)
			(thermal_bridge_width 0.5)
			(island_removal_mode 0)
		)
		(polygon
			(pts
				(xy 41.654984 -17.437608)
				(arc
					(start 56.654192 -17.437608)
					(mid 56.817659 -17.367649)
					(end 56.887618 -17.204182)
				)
				(xy 56.887618 -14.893544) (xy 56.821832 -14.827758) (xy 56.458866 -14.827758) (xy 55.394098 -15.892526)
				(xy 55.394098 -15.896082) (xy 52.367434 -15.896082) (xy 51.397916 -16.8656) (xy 43.902376 -16.8656)
				(xy 43.485816 -16.44904) (xy 43.485816 -13.094208) (xy 42.912792 -12.521184) (xy 41.75506 -12.521184)
				(xy 41.565068 -12.521184) (xy 41.53154 -12.521184) (xy 41.412668 -12.640056) (xy 41.412668 -17.195292)
				(arc
					(start 41.412668 -17.201896)
					(mid 41.483837 -17.367517)
					(end 41.649904 -17.437608)
				)
			)
		)
	)
	(zone
		(layer "F.Cu")
		(hatch none 0.5)
		(connect_pads
			(clearance 0)
		)
		(min_thickness 0.25)
		(keepout
			(tracks not_allowed)
			(vias allowed)
			(pads allowed)
			(copperpour not_allowed)
			(footprints allowed)
		)
		(placement
			(enabled no)
			(sheetname "")
		)
		(fill
			(thermal_gap 0.5)
			(thermal_bridge_width 0.5)
			(island_removal_mode 0)
		)
		(polygon
			(pts
				(arc
					(start 73.699878 -4.99999)
					(mid 76.700126 -1.999742)
					(end 79.70012 -4.99999)
				)
				(arc
					(start 79.70012 -4.99999)
					(mid 76.700126 -7.999984)
					(end 73.699878 -4.99999)
				)
			)
		)
	)
	(zone
		(layer "F.Cu")
		(hatch none 0.5)
		(connect_pads
			(clearance 0)
		)
		(min_thickness 0.25)
		(keepout
			(tracks not_allowed)
			(vias allowed)
			(pads allowed)
			(copperpour not_allowed)
			(footprints allowed)
		)
		(placement
			(enabled no)
			(sheetname "")
		)
		(fill
			(thermal_gap 0.5)
			(thermal_bridge_width 0.5)
			(island_removal_mode 0)
		)
		(polygon
			(pts
				(arc
					(start 183.874918 -4.99999)
					(mid 180.874924 -7.999984)
					(end 177.87493 -4.99999)
				)
				(arc
					(start 177.87493 -4.99999)
					(mid 180.874924 -1.999996)
					(end 183.874918 -4.99999)
				)
			)
		)
	)
	(zone
		(layer "F.Cu")
		(hatch none 0.5)
		(connect_pads
			(clearance 0)
		)
		(min_thickness 0.25)
		(keepout
			(tracks allowed)
			(vias allowed)
			(pads allowed)
			(copperpour allowed)
			(footprints not_allowed)
		)
		(placement
			(enabled no)
			(sheetname "")
		)
		(fill
			(thermal_gap 0.5)
			(thermal_bridge_width 0.5)
			(island_removal_mode 0)
		)
		(polygon
			(pts
				(arc
					(start 1.124966 -4.99999)
					(mid 4.12496 -1.999996)
					(end 7.124954 -4.99999)
				)
				(arc
					(start 7.124954 -4.99999)
					(mid 4.12496 -7.999984)
					(end 1.124966 -4.99999)
				)
			)
		)
	)
	(zone
		(layer "F.Cu")
		(hatch none 0.5)
		(connect_pads
			(clearance 0)
		)
		(min_thickness 0.25)
		(keepout
			(tracks allowed)
			(vias allowed)
			(pads allowed)
			(copperpour allowed)
			(footprints not_allowed)
		)
		(placement
			(enabled no)
			(sheetname "")
		)
		(fill
			(thermal_gap 0.5)
			(thermal_bridge_width 0.5)
			(island_removal_mode 0)
		)
		(polygon
			(pts
				(arc
					(start 73.699878 -4.99999)
					(mid 76.700126 -1.999742)
					(end 79.70012 -4.99999)
				)
				(arc
					(start 79.70012 -4.99999)
					(mid 76.700126 -7.999984)
					(end 73.699878 -4.99999)
				)
			)
		)
	)
	(zone
		(layer "F.Cu")
		(hatch none 0.5)
		(connect_pads
			(clearance 0)
		)
		(min_thickness 0.25)
		(keepout
			(tracks allowed)
			(vias allowed)
			(pads allowed)
			(copperpour allowed)
			(footprints not_allowed)
		)
		(placement
			(enabled no)
			(sheetname "")
		)
		(fill
			(thermal_gap 0.5)
			(thermal_bridge_width 0.5)
			(island_removal_mode 0)
		)
		(polygon
			(pts
				(arc
					(start 121.12498 -4.99999)
					(mid 124.124974 -1.999996)
					(end 127.124968 -4.99999)
				)
				(arc
					(start 127.124968 -4.99999)
					(mid 124.124974 -7.999984)
					(end 121.12498 -4.99999)
				)
			)
		)
	)
	(zone
		(net "P5V_A")
		(layer "F.Cu")
		(hatch none 0.5)
		(connect_pads
			(clearance 0.5)
		)
		(min_thickness 0.25)
		(fill yes
			(thermal_gap 0.5)
			(thermal_bridge_width 0.5)
			(island_removal_mode 0)
		)
		(polygon
			(pts
				(xy 42.613326 -8.056626) (xy 48.3108 -13.7541) (xy 48.3108 -14.3002) (xy 48.3108 -16.418306) (xy 48.415194 -16.5227)
				(xy 50.9397 -16.5227) (xy 51.0413 -16.4211) (xy 51.0413 -14.3637) (xy 51.0413 -13.893546) (xy 42.7609 -5.613146)
				(xy 42.59707 -5.449316) (xy 42.371772 -5.224018) (xy 41.646348 -5.224018) (xy 40.839136 -6.03123)
				(xy 40.839136 -6.282436)
			)
		)
	)
	(zone
		(layer "F.Cu")
		(hatch none 0.5)
		(connect_pads
			(clearance 0)
		)
		(min_thickness 0.25)
		(keepout
			(tracks not_allowed)
			(vias allowed)
			(pads allowed)
			(copperpour not_allowed)
			(footprints allowed)
		)
		(placement
			(enabled no)
			(sheetname "")
		)
		(fill
			(thermal_gap 0.5)
			(thermal_bridge_width 0.5)
			(island_removal_mode 0)
		)
		(polygon
			(pts
				(arc
					(start 7.124954 -4.99999)
					(mid 4.12496 -7.999984)
					(end 1.124966 -4.99999)
				)
				(arc
					(start 1.124966 -4.99999)
					(mid 4.12496 -1.999996)
					(end 7.124954 -4.99999)
				)
			)
		)
	)
	(zone
		(layer "F.Cu")
		(hatch none 0.5)
		(connect_pads
			(clearance 0)
		)
		(min_thickness 0.25)
		(keepout
			(tracks allowed)
			(vias allowed)
			(pads allowed)
			(copperpour allowed)
			(footprints not_allowed)
		)
		(placement
			(enabled no)
			(sheetname "")
		)
		(fill
			(thermal_gap 0.5)
			(thermal_bridge_width 0.5)
			(island_removal_mode 0)
		)
		(polygon
			(pts
				(arc
					(start 7.124954 -4.99999)
					(mid 4.12496 -7.999984)
					(end 1.124966 -4.99999)
				)
				(arc
					(start 1.124966 -4.99999)
					(mid 4.12496 -1.999996)
					(end 7.124954 -4.99999)
				)
			)
		)
	)
	(zone
		(net "GND")
		(layer "F.Cu")
		(hatch none 0.5)
		(connect_pads
			(clearance 0.5)
		)
		(min_thickness 0.25)
		(fill yes
			(thermal_gap 0.5)
			(thermal_bridge_width 0.5)
			(island_removal_mode 0)
		)
		(polygon
			(pts
				(arc
					(start 0.999998 0.237744)
					(mid 0.831888 0.16811)
					(end 0.762254 0)
				)
				(arc
					(start 0.762254 -8.999982)
					(mid 0.831888 -9.168092)
					(end 0.999998 -9.237726)
				)
				(arc
					(start 8.599932 -9.237726)
					(mid 9.846032 -9.753878)
					(end 10.362184 -10.999978)
				)
				(xy 10.362184 -15.162784)
				(arc
					(start 10.362184 -16.200882)
					(mid 10.43225 -16.368516)
					(end 10.600182 -16.437864)
				)
				(xy 11.491214 -16.437864) (xy 11.54938 -16.379698) (xy 11.54938 -15.337536) (xy 11.54938 -12.96162)
				(xy 12.0142 -12.4968) (xy 15.367 -12.4968) (xy 15.621 -12.7508) (xy 15.621 -15.3162) (xy 15.621 -16.404844)
				(xy 15.65402 -16.437864)
				(arc
					(start 16.602456 -16.437864)
					(mid 16.767658 -16.368041)
					(end 16.83766 -16.202914)
				)
				(xy 16.83766 -15.180818)
				(arc
					(start 16.83766 -10.999978)
					(mid 17.353812 -9.753878)
					(end 18.599912 -9.237726)
				)
				(xy 25.407874 -9.237726) (xy 25.4762 -9.1694) (xy 25.4762 -7.3152) (xy 25.7048 -7.0866) (xy 25.712674 -7.078726)
				(xy 39.21252 -7.078726) (xy 39.255446 -7.0358) (xy 41.355264 -4.935982) (xy 41.405556 -4.88569)
				(xy 42.723308 -4.88569) (xy 42.7736 -4.935982) (xy 43.019218 -5.1816) (xy 51.447954 -13.610336)
				(xy 54.962552 -13.610336) (xy 55.500016 -13.072872) (xy 55.500016 -11.100816) (xy 55.500016 -9.806686)
				(xy 56.069738 -9.236964) (xy 64.532764 -9.236964) (xy 64.533018 -9.236964) (xy 70.171564 -9.236964)
				(xy 70.172326 -9.237726)
				(arc
					(start 71.699882 -9.237726)
					(mid 72.945982 -9.753878)
					(end 73.462134 -10.999978)
				)
				(xy 73.462134 -15.169134)
				(arc
					(start 73.462134 -16.202152)
					(mid 73.532481 -16.368953)
					(end 73.699878 -16.437864)
				)
				(xy 74.526394 -16.437864) (xy 74.602848 -16.36141) (xy 74.602848 -15.29334) (xy 74.602848 -13.484352)
				(xy 75.6412 -12.446) (xy 76.004928 -12.446) (xy 76.80833 -11.642598) (xy 77.47889 -11.642598) (xy 78.736698 -12.900406)
				(xy 78.736698 -13.190982) (xy 78.736698 -16.33855) (xy 78.836012 -16.437864)
				(arc
					(start 79.70012 -16.437864)
					(mid 79.865932 -16.367906)
					(end 79.937864 -16.202914)
				)
				(xy 79.937864 -15.210536)
				(arc
					(start 79.937864 -10.999978)
					(mid 80.454016 -9.753878)
					(end 81.700116 -9.237726)
				)
				(arc
					(start 103.249984 -9.237726)
					(mid 104.496084 -9.753878)
					(end 105.012236 -10.999978)
				)
				(xy 105.012236 -15.197836)
				(arc
					(start 105.012236 -16.200882)
					(mid 105.082391 -16.368353)
					(end 105.250234 -16.43761)
				)
				(xy 106.151934 -16.43761) (xy 106.254296 -16.335248) (xy 106.254296 -15.325344) (xy 106.254296 -13.368782)
				(xy 106.999278 -12.6238) (xy 109.6772 -12.6238) (xy 110.2868 -13.2334) (xy 110.2868 -15.394686)
				(xy 110.2868 -16.306038) (xy 110.418626 -16.437864)
				(arc
					(start 111.249968 -16.437864)
					(mid 111.418063 -16.368395)
					(end 111.487712 -16.200374)
				)
				(xy 111.487712 -15.207488)
				(arc
					(start 111.487712 -10.999978)
					(mid 112.003864 -9.753878)
					(end 113.249964 -9.237726)
				)
				(arc
					(start 134.800086 -9.237726)
					(mid 136.046186 -9.753878)
					(end 136.562338 -10.999978)
				)
				(xy 136.562338 -15.204186)
				(arc
					(start 136.562338 -16.202406)
					(mid 136.632774 -16.369044)
					(end 136.800082 -16.437864)
				)
				(xy 137.761726 -16.437864) (xy 137.78611 -16.41348) (xy 137.78611 -15.368524) (xy 137.78611 -13.03909)
				(xy 138.2014 -12.6238) (xy 141.3002 -12.6238) (xy 141.859 -13.1826) (xy 141.859 -15.367) (xy 141.859 -16.407638)
				(xy 141.889226 -16.437864)
				(arc
					(start 142.80007 -16.437864)
					(mid 142.967641 -16.368768)
					(end 143.037814 -16.201644)
				)
				(xy 143.037814 -15.178786)
				(arc
					(start 143.037814 -10.999978)
					(mid 143.553966 -9.753878)
					(end 144.800066 -9.237726)
				)
				(arc
					(start 166.349934 -9.237726)
					(mid 167.596034 -9.753878)
					(end 168.112186 -10.999978)
				)
				(xy 168.112186 -15.876778)
				(arc
					(start 168.112186 -16.20012)
					(mid 168.18182 -16.36823)
					(end 168.34993 -16.437864)
				)
				(xy 169.070782 -16.437864) (xy 169.179748 -16.328898) (xy 169.179748 -15.84706) (xy 169.179748 -13.420344)
				(xy 169.900092 -12.7) (xy 172.74667 -12.7) (xy 173.339252 -13.292836) (xy 173.340014 -13.293598)
				(xy 173.362112 -13.315696) (xy 173.362112 -15.381986) (xy 173.362112 -16.369284) (xy 173.430438 -16.43761)
				(arc
					(start 174.356522 -16.43761)
					(mid 174.519037 -16.365465)
					(end 174.587662 -16.20139)
				)
				(xy 174.587662 -15.185644)
				(arc
					(start 174.587662 -10.999978)
					(mid 175.103814 -9.753878)
					(end 176.349914 -9.237726)
				)
				(arc
					(start 183.999886 -9.237726)
					(mid 184.167996 -9.168092)
					(end 184.23763 -8.999982)
				)
				(arc
					(start 184.23763 0)
					(mid 184.167996 0.16811)
					(end 183.999886 0.237744)
				)
			)
		)
	)
	(zone
		(layer "F.Cu")
		(hatch none 0.5)
		(connect_pads
			(clearance 0)
		)
		(min_thickness 0.25)
		(keepout
			(tracks not_allowed)
			(vias allowed)
			(pads allowed)
			(copperpour not_allowed)
			(footprints allowed)
		)
		(placement
			(enabled no)
			(sheetname "")
		)
		(fill
			(thermal_gap 0.5)
			(thermal_bridge_width 0.5)
			(island_removal_mode 0)
		)
		(polygon
			(pts
				(arc
					(start 121.12498 -4.99999)
					(mid 124.124974 -1.999996)
					(end 127.124968 -4.99999)
				)
				(arc
					(start 127.124968 -4.99999)
					(mid 124.124974 -7.999984)
					(end 121.12498 -4.99999)
				)
			)
		)
	)
	(zone
		(layer "F.Cu")
		(hatch none 0.5)
		(connect_pads
			(clearance 0)
		)
		(min_thickness 0.25)
		(keepout
			(tracks allowed)
			(vias allowed)
			(pads allowed)
			(copperpour allowed)
			(footprints not_allowed)
		)
		(placement
			(enabled no)
			(sheetname "")
		)
		(fill
			(thermal_gap 0.5)
			(thermal_bridge_width 0.5)
			(island_removal_mode 0)
		)
		(polygon
			(pts
				(arc
					(start 0.999998 -9.99998)
					(mid 0.292893 -9.707087)
					(end 0 -8.999982)
				)
				(arc
					(start 0 0)
					(mid 0.292893 0.707105)
					(end 0.999998 0.999998)
				)
				(arc
					(start 183.999886 0.999998)
					(mid 184.706991 0.707105)
					(end 184.999884 0)
				)
				(arc
					(start 184.999884 -8.999982)
					(mid 184.706991 -9.707087)
					(end 183.999886 -9.99998)
				)
				(arc
					(start 176.349914 -9.99998)
					(mid 175.642809 -10.292873)
					(end 175.349916 -10.999978)
				)
				(arc
					(start 175.349916 -16.20012)
					(mid 175.057023 -16.907225)
					(end 174.349918 -17.200118)
				)
				(arc
					(start 168.34993 -17.200118)
					(mid 167.642825 -16.907225)
					(end 167.349932 -16.20012)
				)
				(arc
					(start 167.349932 -10.999978)
					(mid 167.057039 -10.292873)
					(end 166.349934 -9.99998)
				)
				(arc
					(start 144.800066 -9.99998)
					(mid 144.092961 -10.292873)
					(end 143.800068 -10.999978)
				)
				(arc
					(start 143.800068 -16.20012)
					(mid 143.507175 -16.907225)
					(end 142.80007 -17.200118)
				)
				(arc
					(start 136.800082 -17.200118)
					(mid 136.092977 -16.907225)
					(end 135.800084 -16.20012)
				)
				(arc
					(start 135.800084 -10.999978)
					(mid 135.507191 -10.292873)
					(end 134.800086 -9.99998)
				)
				(arc
					(start 113.249964 -9.99998)
					(mid 112.542859 -10.292873)
					(end 112.249966 -10.999978)
				)
				(arc
					(start 112.249966 -16.20012)
					(mid 111.957073 -16.907225)
					(end 111.249968 -17.200118)
				)
				(arc
					(start 105.24998 -17.200118)
					(mid 104.542875 -16.907225)
					(end 104.249982 -16.20012)
				)
				(arc
					(start 104.249982 -10.999978)
					(mid 103.957089 -10.292873)
					(end 103.249984 -9.99998)
				)
				(arc
					(start 81.700116 -9.99998)
					(mid 80.993011 -10.292873)
					(end 80.700118 -10.999978)
				)
				(arc
					(start 80.700118 -16.20012)
					(mid 80.407225 -16.907225)
					(end 79.70012 -17.200118)
				)
				(arc
					(start 73.699878 -17.200118)
					(mid 72.992773 -16.907225)
					(end 72.69988 -16.20012)
				)
				(arc
					(start 72.69988 -10.999978)
					(mid 72.406987 -10.292873)
					(end 71.699882 -9.99998)
				)
				(arc
					(start 58.650124 -9.99998)
					(mid 57.943019 -10.292873)
					(end 57.650126 -10.999978)
				)
				(arc
					(start 57.650126 -17.200118)
					(mid 57.357144 -17.907313)
					(end 56.649874 -18.200116)
				)
				(arc
					(start 41.649904 -18.200116)
					(mid 40.942799 -17.907223)
					(end 40.649906 -17.200118)
				)
				(arc
					(start 40.649906 -10.999978)
					(mid 40.357013 -10.292873)
					(end 39.649908 -9.99998)
				)
				(arc
					(start 18.599912 -9.99998)
					(mid 17.892807 -10.292873)
					(end 17.599914 -10.999978)
				)
				(arc
					(start 17.599914 -16.20012)
					(mid 17.307021 -16.907225)
					(end 16.599916 -17.200118)
				)
				(arc
					(start 10.599928 -17.200118)
					(mid 9.892823 -16.907225)
					(end 9.59993 -16.20012)
				)
				(arc
					(start 9.59993 -10.999978)
					(mid 9.307037 -10.292873)
					(end 8.599932 -9.99998)
				)
			)
		)
	)
	(zone
		(layer "F.Cu")
		(hatch none 0.5)
		(connect_pads
			(clearance 0)
		)
		(min_thickness 0.25)
		(keepout
			(tracks allowed)
			(vias allowed)
			(pads allowed)
			(copperpour allowed)
			(footprints not_allowed)
		)
		(placement
			(enabled no)
			(sheetname "")
		)
		(fill
			(thermal_gap 0.5)
			(thermal_bridge_width 0.5)
			(island_removal_mode 0)
		)
		(polygon
			(pts
				(arc
					(start 177.87493 -4.99999)
					(mid 180.874924 -1.999996)
					(end 183.874918 -4.99999)
				)
				(arc
					(start 183.874918 -4.99999)
					(mid 180.874924 -7.999984)
					(end 177.87493 -4.99999)
				)
			)
		)
	)
	(zone
		(layer "F.Cu")
		(hatch none 0.5)
		(connect_pads
			(clearance 0)
		)
		(min_thickness 0.25)
		(keepout
			(tracks allowed)
			(vias allowed)
			(pads allowed)
			(copperpour allowed)
			(footprints not_allowed)
		)
		(placement
			(enabled no)
			(sheetname "")
		)
		(fill
			(thermal_gap 0.5)
			(thermal_bridge_width 0.5)
			(island_removal_mode 0)
		)
		(polygon
			(pts
				(arc
					(start 183.874918 -4.99999)
					(mid 180.874924 -7.999984)
					(end 177.87493 -4.99999)
				)
				(arc
					(start 177.87493 -4.99999)
					(mid 180.874924 -1.999996)
					(end 183.874918 -4.99999)
				)
			)
		)
	)
	(zone
		(layer "F.Cu")
		(hatch none 0.5)
		(connect_pads
			(clearance 0)
		)
		(min_thickness 0.25)
		(keepout
			(tracks allowed)
			(vias allowed)
			(pads allowed)
			(copperpour allowed)
			(footprints not_allowed)
		)
		(placement
			(enabled no)
			(sheetname "")
		)
		(fill
			(thermal_gap 0.5)
			(thermal_bridge_width 0.5)
			(island_removal_mode 0)
		)
		(polygon
			(pts
				(arc
					(start 13.57503 -4.99999)
					(mid 12.125198 -6.449822)
					(end 10.675112 -4.99999)
				)
				(arc
					(start 10.675112 -4.99999)
					(mid 12.125198 -3.549904)
					(end 13.57503 -4.99999)
				)
			)
		)
	)
	(zone
		(layers "F.Cu" "B.Cu")
		(name "Route Keepin")
		(hatch none 0.5)
		(connect_pads
			(clearance 0)
		)
		(min_thickness 0.25)
		(keepout
			(tracks allowed)
			(vias allowed)
			(pads allowed)
			(copperpour allowed)
			(footprints allowed)
		)
		(placement
			(enabled no)
			(sheetname "")
		)
		(fill
			(thermal_gap 0.5)
			(thermal_bridge_width 0.5)
			(island_removal_mode 0)
		)
		(polygon
			(pts
				(arc
					(start 142.80007 -16.438118)
					(mid 142.96836 -16.36841)
					(end 143.038068 -16.20012)
				)
				(arc
					(start 143.038068 -10.999978)
					(mid 143.554145 -9.754057)
					(end 144.800066 -9.23798)
				)
				(arc
					(start 166.349934 -9.23798)
					(mid 167.595855 -9.754057)
					(end 168.111932 -10.999978)
				)
				(arc
					(start 168.111932 -16.20012)
					(mid 168.18164 -16.36841)
					(end 168.34993 -16.438118)
				)
				(arc
					(start 174.349918 -16.438118)
					(mid 174.518208 -16.36841)
					(end 174.587916 -16.20012)
				)
				(arc
					(start 174.587916 -10.999978)
					(mid 175.103993 -9.754057)
					(end 176.349914 -9.23798)
				)
				(arc
					(start 183.999886 -9.23798)
					(mid 184.168176 -9.168272)
					(end 184.237884 -8.999982)
				)
				(arc
					(start 184.237884 0)
					(mid 184.168176 0.16829)
					(end 183.999886 0.237998)
				)
				(arc
					(start 0.999998 0.237998)
					(mid 0.831708 0.16829)
					(end 0.762 0)
				)
				(arc
					(start 0.762 -8.999982)
					(mid 0.831708 -9.168272)
					(end 0.999998 -9.23798)
				)
				(arc
					(start 8.599932 -9.23798)
					(mid 9.845853 -9.754057)
					(end 10.36193 -10.999978)
				)
				(arc
					(start 10.36193 -16.20012)
					(mid 10.431638 -16.36841)
					(end 10.599928 -16.438118)
				)
				(arc
					(start 16.599916 -16.438118)
					(mid 16.768206 -16.36841)
					(end 16.837914 -16.20012)
				)
				(arc
					(start 16.837914 -10.999978)
					(mid 17.353991 -9.754057)
					(end 18.599912 -9.23798)
				)
				(arc
					(start 39.649908 -9.23798)
					(mid 40.895829 -9.754057)
					(end 41.411906 -10.999978)
				)
				(arc
					(start 41.411906 -17.200118)
					(mid 41.481614 -17.368408)
					(end 41.649904 -17.438116)
				)
				(arc
					(start 56.650128 -17.438116)
					(mid 56.818418 -17.368408)
					(end 56.888126 -17.200118)
				)
				(arc
					(start 56.888126 -10.999978)
					(mid 57.404203 -9.754057)
					(end 58.650124 -9.23798)
				)
				(arc
					(start 71.699882 -9.23798)
					(mid 72.945803 -9.754057)
					(end 73.46188 -10.999978)
				)
				(arc
					(start 73.46188 -16.20012)
					(mid 73.531588 -16.36841)
					(end 73.699878 -16.438118)
				)
				(arc
					(start 79.70012 -16.438118)
					(mid 79.86841 -16.36841)
					(end 79.938118 -16.20012)
				)
				(arc
					(start 79.938118 -10.999978)
					(mid 80.454195 -9.754057)
					(end 81.700116 -9.23798)
				)
				(arc
					(start 103.249984 -9.23798)
					(mid 104.495905 -9.754057)
					(end 105.011982 -10.999978)
				)
				(arc
					(start 105.011982 -16.20012)
					(mid 105.08169 -16.36841)
					(end 105.24998 -16.438118)
				)
				(arc
					(start 111.249968 -16.438118)
					(mid 111.418258 -16.36841)
					(end 111.487966 -16.20012)
				)
				(arc
					(start 111.487966 -10.999978)
					(mid 112.004043 -9.754057)
					(end 113.249964 -9.23798)
				)
				(arc
					(start 134.800086 -9.23798)
					(mid 136.046007 -9.754057)
					(end 136.562084 -10.999978)
				)
				(arc
					(start 136.562084 -16.20012)
					(mid 136.631792 -16.36841)
					(end 136.800082 -16.438118)
				)
			)
		)
	)
	(zone
		(layers "F.Cu" "B.Cu")
		(name "Package Keepin")
		(hatch none 0.5)
		(connect_pads
			(clearance 0)
		)
		(min_thickness 0.25)
		(keepout
			(tracks allowed)
			(vias allowed)
			(pads allowed)
			(copperpour allowed)
			(footprints allowed)
		)
		(placement
			(enabled no)
			(sheetname "")
		)
		(fill
			(thermal_gap 0.5)
			(thermal_bridge_width 0.5)
			(island_removal_mode 0)
		)
		(polygon
			(pts
				(xy 141.768068 -15.168118)
				(arc
					(start 141.768068 -10.999978)
					(mid 142.65612 -8.856032)
					(end 144.800066 -7.96798)
				)
				(arc
					(start 166.349934 -7.96798)
					(mid 168.49388 -8.856032)
					(end 169.381932 -10.999978)
				)
				(xy 169.381932 -15.168118) (xy 173.317916 -15.168118)
				(arc
					(start 173.317916 -10.999978)
					(mid 174.205968 -8.856032)
					(end 176.349914 -7.96798)
				)
				(xy 182.967884 -7.96798) (xy 182.967884 -1.032002) (xy 2.032 -1.032002) (xy 2.032 -7.96798)
				(arc
					(start 8.599932 -7.96798)
					(mid 10.743878 -8.856032)
					(end 11.63193 -10.999978)
				)
				(xy 11.63193 -15.168118) (xy 15.567914 -15.168118)
				(arc
					(start 15.567914 -10.999978)
					(mid 16.455966 -8.856032)
					(end 18.599912 -7.96798)
				)
				(arc
					(start 39.649908 -7.96798)
					(mid 41.793854 -8.856032)
					(end 42.681906 -10.999978)
				)
				(xy 42.681906 -16.168116) (xy 55.618126 -16.168116)
				(arc
					(start 55.618126 -10.999978)
					(mid 56.506178 -8.856032)
					(end 58.650124 -7.96798)
				)
				(arc
					(start 71.699882 -7.96798)
					(mid 73.843828 -8.856032)
					(end 74.73188 -10.999978)
				)
				(xy 74.73188 -15.168118) (xy 78.668118 -15.168118)
				(arc
					(start 78.668118 -10.999978)
					(mid 79.55617 -8.856032)
					(end 81.700116 -7.96798)
				)
				(arc
					(start 103.249984 -7.96798)
					(mid 105.39393 -8.856032)
					(end 106.281982 -10.999978)
				)
				(xy 106.281982 -15.168118) (xy 110.217966 -15.168118)
				(arc
					(start 110.217966 -10.999978)
					(mid 111.106018 -8.856032)
					(end 113.249964 -7.96798)
				)
				(arc
					(start 134.800086 -7.96798)
					(mid 136.944032 -8.856032)
					(end 137.832084 -10.999978)
				)
				(xy 137.832084 -15.168118)
			)
		)
	)
	(zone
		(layer "B.Cu")
		(hatch none 0.5)
		(connect_pads
			(clearance 0)
		)
		(min_thickness 0.25)
		(keepout
			(tracks allowed)
			(vias allowed)
			(pads allowed)
			(copperpour allowed)
			(footprints not_allowed)
		)
		(placement
			(enabled no)
			(sheetname "")
		)
		(fill
			(thermal_gap 0.5)
			(thermal_bridge_width 0.5)
			(island_removal_mode 0)
		)
		(polygon
			(pts
				(arc
					(start 177.87493 -4.99999)
					(mid 180.874924 -7.999984)
					(end 183.874918 -4.99999)
				)
				(arc
					(start 183.874918 -4.99999)
					(mid 180.874924 -1.999996)
					(end 177.87493 -4.99999)
				)
			)
		)
	)
	(zone
		(layer "B.Cu")
		(hatch none 0.5)
		(connect_pads
			(clearance 0)
		)
		(min_thickness 0.25)
		(keepout
			(tracks not_allowed)
			(vias allowed)
			(pads allowed)
			(copperpour not_allowed)
			(footprints allowed)
		)
		(placement
			(enabled no)
			(sheetname "")
		)
		(fill
			(thermal_gap 0.5)
			(thermal_bridge_width 0.5)
			(island_removal_mode 0)
		)
		(polygon
			(pts
				(arc
					(start 183.874918 -4.99999)
					(mid 180.874924 -1.999996)
					(end 177.87493 -4.99999)
				)
				(arc
					(start 177.87493 -4.99999)
					(mid 180.874924 -7.999984)
					(end 183.874918 -4.99999)
				)
			)
		)
	)
	(zone
		(layer "B.Cu")
		(hatch none 0.5)
		(connect_pads
			(clearance 0)
		)
		(min_thickness 0.25)
		(keepout
			(tracks allowed)
			(vias allowed)
			(pads allowed)
			(copperpour allowed)
			(footprints not_allowed)
		)
		(placement
			(enabled no)
			(sheetname "")
		)
		(fill
			(thermal_gap 0.5)
			(thermal_bridge_width 0.5)
			(island_removal_mode 0)
		)
		(polygon
			(pts
				(arc
					(start 10.675112 -4.99999)
					(mid 12.125198 -6.450076)
					(end 13.57503 -4.99999)
				)
				(arc
					(start 13.57503 -4.99999)
					(mid 12.125198 -3.550158)
					(end 10.675112 -4.99999)
				)
			)
		)
	)
	(zone
		(net "GND")
		(layer "B.Cu")
		(hatch none 0.5)
		(connect_pads
			(clearance 0.5)
		)
		(min_thickness 0.25)
		(fill yes
			(thermal_gap 0.5)
			(thermal_bridge_width 0.5)
			(island_removal_mode 0)
		)
		(polygon
			(pts
				(xy 111.982504 -1.271016) (xy 111.783368 -1.470152) (xy 111.783368 -4.17195) (xy 111.992918 -4.3815)
				(xy 117.27942 -4.3815) (xy 120.047512 -7.149592) (xy 120.631204 -7.149592) (xy 121.083832 -6.696964)
				(xy 121.083832 -4.931918) (xy 122.58929 -3.42646) (xy 127.019558 -3.42646) (xy 127.019558 -4.106418)
				(xy 127.622808 -4.709668) (xy 128.56718 -4.709668) (xy 128.88214 -4.394708) (xy 128.954784 -4.322064)
				(xy 136.568434 -4.322064) (xy 136.641078 -4.394708) (xy 136.916668 -4.670298) (xy 136.916668 -5.319776)
				(xy 136.910318 -5.326126) (xy 137.09396 -5.509768) (xy 137.94994 -5.509768) (xy 138.24839 -5.211318)
				(xy 138.24839 -4.286758) (xy 138.658092 -3.877056) (xy 138.658092 -3.07467) (xy 138.657584 -3.074162)
				(xy 138.657584 -2.951226) (xy 136.977374 -1.271016)
			)
		)
	)
	(zone
		(layer "B.Cu")
		(hatch none 0.5)
		(connect_pads
			(clearance 0)
		)
		(min_thickness 0.25)
		(keepout
			(tracks allowed)
			(vias allowed)
			(pads allowed)
			(copperpour allowed)
			(footprints not_allowed)
		)
		(placement
			(enabled no)
			(sheetname "")
		)
		(fill
			(thermal_gap 0.5)
			(thermal_bridge_width 0.5)
			(island_removal_mode 0)
		)
		(polygon
			(pts
				(arc
					(start 7.124954 -4.99999)
					(mid 4.12496 -1.999996)
					(end 1.124966 -4.99999)
				)
				(arc
					(start 1.124966 -4.99999)
					(mid 4.12496 -7.999984)
					(end 7.124954 -4.99999)
				)
			)
		)
	)
	(zone
		(layer "B.Cu")
		(hatch none 0.5)
		(connect_pads
			(clearance 0)
		)
		(min_thickness 0.25)
		(keepout
			(tracks not_allowed)
			(vias allowed)
			(pads allowed)
			(copperpour not_allowed)
			(footprints allowed)
		)
		(placement
			(enabled no)
			(sheetname "")
		)
		(fill
			(thermal_gap 0.5)
			(thermal_bridge_width 0.5)
			(island_removal_mode 0)
		)
		(polygon
			(pts
				(arc
					(start 7.124954 -4.99999)
					(mid 4.12496 -1.999996)
					(end 1.124966 -4.99999)
				)
				(arc
					(start 1.124966 -4.99999)
					(mid 4.12496 -7.999984)
					(end 7.124954 -4.99999)
				)
			)
		)
	)
	(zone
		(net "P5V_A")
		(layer "B.Cu")
		(hatch none 0.5)
		(connect_pads
			(clearance 0.5)
		)
		(min_thickness 0.25)
		(fill yes
			(thermal_gap 0.5)
			(thermal_bridge_width 0.5)
			(island_removal_mode 0)
		)
		(polygon
			(pts
				(xy 24.1046 -5.7912) (xy 26.5176 -5.7912) (xy 26.67 -5.6388) (xy 26.67 -3.9878) (xy 26.543 -3.8608)
				(xy 24.2316 -3.8608) (xy 24.0284 -4.064) (xy 24.0284 -5.715)
			)
		)
	)
	(zone
		(layer "B.Cu")
		(hatch none 0.5)
		(connect_pads
			(clearance 0)
		)
		(min_thickness 0.25)
		(keepout
			(tracks allowed)
			(vias allowed)
			(pads allowed)
			(copperpour allowed)
			(footprints not_allowed)
		)
		(placement
			(enabled no)
			(sheetname "")
		)
		(fill
			(thermal_gap 0.5)
			(thermal_bridge_width 0.5)
			(island_removal_mode 0)
		)
		(polygon
			(pts
				(arc
					(start 121.12498 -4.99999)
					(mid 124.124974 -7.999984)
					(end 127.124968 -4.99999)
				)
				(arc
					(start 127.124968 -4.99999)
					(mid 124.124974 -1.999996)
					(end 121.12498 -4.99999)
				)
			)
		)
	)
	(zone
		(layer "B.Cu")
		(hatch none 0.5)
		(connect_pads
			(clearance 0)
		)
		(min_thickness 0.25)
		(keepout
			(tracks not_allowed)
			(vias allowed)
			(pads allowed)
			(copperpour not_allowed)
			(footprints allowed)
		)
		(placement
			(enabled no)
			(sheetname "")
		)
		(fill
			(thermal_gap 0.5)
			(thermal_bridge_width 0.5)
			(island_removal_mode 0)
		)
		(polygon
			(pts
				(arc
					(start 125.400054 -4.99999)
					(mid 124.124974 -3.72491)
					(end 122.849894 -4.99999)
				)
				(arc
					(start 122.849894 -4.99999)
					(mid 124.124974 -6.27507)
					(end 125.400054 -4.99999)
				)
			)
		)
	)
	(zone
		(layer "B.Cu")
		(hatch none 0.5)
		(connect_pads
			(clearance 0)
		)
		(min_thickness 0.25)
		(keepout
			(tracks allowed)
			(vias allowed)
			(pads allowed)
			(copperpour allowed)
			(footprints not_allowed)
		)
		(placement
			(enabled no)
			(sheetname "")
		)
		(fill
			(thermal_gap 0.5)
			(thermal_bridge_width 0.5)
			(island_removal_mode 0)
		)
		(polygon
			(pts
				(arc
					(start 73.699878 -4.99999)
					(mid 76.700126 -8.000238)
					(end 79.70012 -4.99999)
				)
				(arc
					(start 79.70012 -4.99999)
					(mid 76.700126 -1.999996)
					(end 73.699878 -4.99999)
				)
			)
		)
	)
	(zone
		(net "GND")
		(layer "B.Cu")
		(hatch none 0.5)
		(connect_pads
			(clearance 0.5)
		)
		(min_thickness 0.25)
		(fill yes
			(thermal_gap 0.5)
			(thermal_bridge_width 0.5)
			(island_removal_mode 0)
		)
		(polygon
			(pts
				(xy 160.412176 -4.483862) (xy 160.412176 -5.352796) (xy 160.476184 -5.416804) (xy 161.488628 -5.416804)
				(xy 161.544762 -5.36067) (xy 161.544762 -3.921252) (xy 161.973768 -3.492246) (xy 161.973768 -2.804922)
				(xy 161.661856 -2.49301) (xy 161.20364 -2.49301) (xy 160.387792 -1.677162) (xy 144.431512 -1.677162)
				(xy 144.132808 -1.975866) (xy 144.132808 -3.852164) (xy 144.452594 -4.17195) (xy 157.032706 -4.17195)
				(xy 160.100264 -4.17195)
			)
		)
	)
	(zone
		(net "GND")
		(layer "B.Cu")
		(hatch none 0.5)
		(connect_pads
			(clearance 0.5)
		)
		(min_thickness 0.25)
		(fill yes
			(thermal_gap 0.5)
			(thermal_bridge_width 0.5)
			(island_removal_mode 0)
		)
		(polygon
			(pts
				(xy 104.9528 -5.7658) (xy 105.7656 -5.7658) (xy 105.9434 -5.588) (xy 105.9434 -4.0132) (xy 106.045 -3.9116)
				(xy 106.4006 -3.9116) (xy 106.4768 -3.8354) (xy 106.4768 -3.2258) (xy 106.2482 -2.9972) (xy 105.388664 -2.137664)
				(xy 80.616298 -2.137664) (xy 80.4418 -2.312162) (xy 80.4418 -3.0988) (xy 80.4418 -4.5466) (xy 80.5688 -4.6736)
				(xy 81.407 -4.6736) (xy 81.7118 -4.3688) (xy 104.648 -4.3688) (xy 104.8258 -4.5466) (xy 104.8258 -5.6388)
			)
		)
	)
	(zone
		(layer "B.Cu")
		(hatch none 0.5)
		(connect_pads
			(clearance 0)
		)
		(min_thickness 0.25)
		(keepout
			(tracks allowed)
			(vias allowed)
			(pads allowed)
			(copperpour allowed)
			(footprints not_allowed)
		)
		(placement
			(enabled no)
			(sheetname "")
		)
		(fill
			(thermal_gap 0.5)
			(thermal_bridge_width 0.5)
			(island_removal_mode 0)
		)
		(polygon
			(pts
				(arc
					(start 144.800066 -9.99998)
					(mid 144.092961 -10.292873)
					(end 143.800068 -10.999978)
				)
				(arc
					(start 143.800068 -16.20012)
					(mid 143.507175 -16.907225)
					(end 142.80007 -17.200118)
				)
				(arc
					(start 136.800082 -17.200118)
					(mid 136.092977 -16.907225)
					(end 135.800084 -16.20012)
				)
				(arc
					(start 135.800084 -10.999978)
					(mid 135.507191 -10.292873)
					(end 134.800086 -9.99998)
				)
				(arc
					(start 113.249964 -9.99998)
					(mid 112.542859 -10.292873)
					(end 112.249966 -10.999978)
				)
				(arc
					(start 112.249966 -16.20012)
					(mid 111.957073 -16.907225)
					(end 111.249968 -17.200118)
				)
				(arc
					(start 105.24998 -17.200118)
					(mid 104.542875 -16.907225)
					(end 104.249982 -16.20012)
				)
				(arc
					(start 104.249982 -10.999978)
					(mid 103.957089 -10.292873)
					(end 103.249984 -9.99998)
				)
				(arc
					(start 81.700116 -9.99998)
					(mid 80.993011 -10.292873)
					(end 80.700118 -10.999978)
				)
				(arc
					(start 80.700118 -16.20012)
					(mid 80.407225 -16.907225)
					(end 79.70012 -17.200118)
				)
				(arc
					(start 73.699878 -17.200118)
					(mid 72.992773 -16.907225)
					(end 72.69988 -16.20012)
				)
				(arc
					(start 72.69988 -10.999978)
					(mid 72.406987 -10.292873)
					(end 71.699882 -9.99998)
				)
				(arc
					(start 58.650124 -9.99998)
					(mid 57.943019 -10.292873)
					(end 57.650126 -10.999978)
				)
				(arc
					(start 57.650126 -17.200118)
					(mid 57.357144 -17.907313)
					(end 56.649874 -18.200116)
				)
				(arc
					(start 41.649904 -18.200116)
					(mid 40.942799 -17.907223)
					(end 40.649906 -17.200118)
				)
				(arc
					(start 40.649906 -10.999978)
					(mid 40.357013 -10.292873)
					(end 39.649908 -9.99998)
				)
				(arc
					(start 18.599912 -9.99998)
					(mid 17.892807 -10.292873)
					(end 17.599914 -10.999978)
				)
				(arc
					(start 17.599914 -16.20012)
					(mid 17.307021 -16.907225)
					(end 16.599916 -17.200118)
				)
				(arc
					(start 10.599928 -17.200118)
					(mid 9.892823 -16.907225)
					(end 9.59993 -16.20012)
				)
				(arc
					(start 9.59993 -10.999978)
					(mid 9.307037 -10.292873)
					(end 8.599932 -9.99998)
				)
				(arc
					(start 0.999998 -9.99998)
					(mid 0.292893 -9.707087)
					(end 0 -8.999982)
				)
				(arc
					(start 0 0)
					(mid 0.292893 0.707105)
					(end 0.999998 0.999998)
				)
				(xy 40.850058 0.999998) (xy 40.850058 -9.59993) (xy 57.449974 -9.59993) (xy 57.449974 0.999998)
				(arc
					(start 183.999886 0.999998)
					(mid 184.706991 0.707105)
					(end 184.999884 0)
				)
				(arc
					(start 184.999884 -8.999982)
					(mid 184.706991 -9.707087)
					(end 183.999886 -9.99998)
				)
				(arc
					(start 176.349914 -9.99998)
					(mid 175.642809 -10.292873)
					(end 175.349916 -10.999978)
				)
				(arc
					(start 175.349916 -16.20012)
					(mid 175.057023 -16.907225)
					(end 174.349918 -17.200118)
				)
				(arc
					(start 168.34993 -17.200118)
					(mid 167.642825 -16.907225)
					(end 167.349932 -16.20012)
				)
				(arc
					(start 167.349932 -10.999978)
					(mid 167.057039 -10.292873)
					(end 166.349934 -9.99998)
				)
			)
		)
	)
	(zone
		(layer "B.Cu")
		(hatch none 0.5)
		(connect_pads
			(clearance 0)
		)
		(min_thickness 0.25)
		(keepout
			(tracks allowed)
			(vias allowed)
			(pads allowed)
			(copperpour allowed)
			(footprints not_allowed)
		)
		(placement
			(enabled no)
			(sheetname "")
		)
		(fill
			(thermal_gap 0.5)
			(thermal_bridge_width 0.5)
			(island_removal_mode 0)
		)
		(polygon
			(pts
				(arc
					(start 1.124966 -4.99999)
					(mid 4.12496 -7.999984)
					(end 7.124954 -4.99999)
				)
				(arc
					(start 7.124954 -4.99999)
					(mid 4.12496 -1.999996)
					(end 1.124966 -4.99999)
				)
			)
		)
	)
	(zone
		(layer "B.Cu")
		(hatch none 0.5)
		(connect_pads
			(clearance 0)
		)
		(min_thickness 0.25)
		(keepout
			(tracks allowed)
			(vias allowed)
			(pads allowed)
			(copperpour allowed)
			(footprints not_allowed)
		)
		(placement
			(enabled no)
			(sheetname "")
		)
		(fill
			(thermal_gap 0.5)
			(thermal_bridge_width 0.5)
			(island_removal_mode 0)
		)
		(polygon
			(pts
				(arc
					(start 183.874918 -4.99999)
					(mid 180.874924 -1.999996)
					(end 177.87493 -4.99999)
				)
				(arc
					(start 177.87493 -4.99999)
					(mid 180.874924 -7.999984)
					(end 183.874918 -4.99999)
				)
			)
		)
	)
	(zone
		(layer "B.Cu")
		(hatch none 0.5)
		(connect_pads
			(clearance 0)
		)
		(min_thickness 0.25)
		(keepout
			(tracks not_allowed)
			(vias allowed)
			(pads allowed)
			(copperpour not_allowed)
			(footprints allowed)
		)
		(placement
			(enabled no)
			(sheetname "")
		)
		(fill
			(thermal_gap 0.5)
			(thermal_bridge_width 0.5)
			(island_removal_mode 0)
		)
		(polygon
			(pts
				(arc
					(start 79.70012 -4.99999)
					(mid 76.700126 -1.999996)
					(end 73.699878 -4.99999)
				)
				(arc
					(start 73.699878 -4.99999)
					(mid 76.700126 -8.000238)
					(end 79.70012 -4.99999)
				)
			)
		)
	)
	(zone
		(net "GND")
		(layer "B.Cu")
		(hatch none 0.5)
		(connect_pads
			(clearance 0.5)
		)
		(min_thickness 0.25)
		(fill yes
			(thermal_gap 0.5)
			(thermal_bridge_width 0.5)
			(island_removal_mode 0)
		)
		(polygon
			(pts
				(arc
					(start 0.999998 0.237744)
					(mid 0.831888 0.16811)
					(end 0.762254 0)
				)
				(arc
					(start 0.762254 -9.002014)
					(mid 0.83188 -9.167846)
					(end 0.997712 -9.237472)
				)
				(arc
					(start 8.60679 -9.237472)
					(mid 9.84848 -9.756205)
					(end 10.362184 -10.999978)
				)
				(arc
					(start 10.362184 -16.199866)
					(mid 10.431892 -16.368156)
					(end 10.600182 -16.437864)
				)
				(arc
					(start 16.601186 -16.437864)
					(mid 16.767809 -16.368013)
					(end 16.83766 -16.20139)
				)
				(arc
					(start 16.83766 -10.94105)
					(mid 17.354821 -9.730651)
					(end 18.572734 -9.231376)
				)
				(arc
					(start 39.649654 -9.231376)
					(mid 40.896309 -9.747915)
					(end 41.412668 -10.994644)
				)
				(arc
					(start 41.412668 -17.200118)
					(mid 41.482227 -17.368049)
					(end 41.650158 -17.437608)
				)
				(arc
					(start 56.654192 -17.437608)
					(mid 56.817659 -17.367649)
					(end 56.887618 -17.204182)
				)
				(arc
					(start 56.887618 -10.988802)
					(mid 57.407599 -9.749401)
					(end 58.650124 -9.236964)
				)
				(xy 71.137272 -9.236964) (xy 71.270622 -9.103614) (xy 71.270622 -8.716518) (xy 71.117714 -8.56361)
				(xy 64.175132 -8.56361) (xy 63.36919 -7.757668) (xy 61.632084 -7.757668) (xy 61.27496 -7.400544)
				(xy 61.27496 -6.705092) (xy 60.580778 -6.01091) (xy 60.580778 -5.163058) (xy 61.058044 -4.685792)
				(xy 62.879478 -4.685792) (xy 63.526924 -5.333238) (xy 64.351154 -5.333238) (xy 64.54648 -5.137912)
				(xy 64.54648 -3.012186) (xy 64.496188 -2.961894) (xy 58.349642 -2.961894) (xy 57.216548 -4.094988)
				(xy 56.817006 -4.094988) (xy 54.924706 -5.987288) (xy 54.924706 -16.237458) (xy 54.308248 -16.853916)
				(xy 47.448724 -16.853916) (xy 47.0154 -16.420592) (xy 47.0154 -14.2494) (xy 46.9646 -14.1986) (xy 44.2976 -14.1986)
				(xy 43.8277 -13.7287) (xy 43.8277 -12.1539) (xy 43.8404 -12.1412) (xy 43.8404 -8.6614) (xy 42.7482 -7.5692)
				(xy 38.8112 -7.5692) (xy 38.481 -7.239) (xy 38.481 -4.572) (xy 37.9984 -4.0894) (xy 36.3982 -4.0894)
				(xy 36.195 -4.2926) (xy 36.195 -5.1054) (xy 35.4838 -5.8166) (xy 35.4838 -7.605776) (xy 34.943288 -8.146288)
				(xy 18.308828 -8.146288) (xy 15.634716 -10.8204) (xy 15.634716 -14.567916) (xy 15.26413 -14.938502)
				(xy 11.89482 -14.938502) (xy 11.54938 -14.593062) (xy 11.54938 -12.70762) (xy 11.7348 -12.5222)
				(xy 11.7348 -11.0998) (xy 14.3256 -8.509) (xy 14.3256 -4.2418) (xy 14.7066 -3.8608) (xy 16.9418 -3.8608)
				(xy 17.1196 -4.0386) (xy 17.1196 -4.9276) (xy 17.272 -5.08) (xy 18.288 -5.08) (xy 18.415 -4.953)
				(xy 18.415 -3.5052) (xy 18.5928 -3.3274) (xy 19.1008 -3.3274) (xy 19.2024 -3.2258) (xy 19.2024 -1.927352)
				(xy 19.37258 -1.757172) (xy 22.808946 -1.757172) (xy 24.086566 -0.479552) (xy 43.06316 -0.479552)
				(xy 47.014892 -4.431284) (xy 48.507142 -4.431284) (xy 52.490878 -0.447548) (xy 166.287704 -0.447548)
				(xy 167.767508 -1.927352) (xy 167.767508 -4.112768) (xy 167.85844 -4.2037) (xy 169.633392 -4.2037)
				(xy 170.001438 -4.571746) (xy 170.001438 -7.151624) (xy 173.53534 -10.685526) (xy 173.53534 -14.022578)
				(xy 173.098206 -14.459712) (xy 169.473626 -14.459712) (xy 169.095166 -14.081252) (xy 169.095166 -10.061448)
				(xy 167.719756 -8.686038) (xy 160.203388 -8.686038) (xy 158.684976 -7.167626) (xy 158.684976 -6.368034)
				(xy 158.345886 -6.028944) (xy 146.678904 -6.028944) (xy 145.252186 -7.455662) (xy 143.647668 -7.455662)
				(xy 141.888718 -9.214612) (xy 141.888718 -14.166596) (xy 141.355826 -14.699488) (xy 138.098784 -14.699488)
				(xy 137.74166 -14.342364) (xy 137.74166 -9.683496) (xy 134.0104 -5.952236) (xy 130.092704 -5.952236)
				(xy 127.246126 -8.798814) (xy 127.246126 -9.134094) (xy 127.349758 -9.237726)
				(arc
					(start 134.808976 -9.237726)
					(mid 136.049341 -9.757009)
					(end 136.562338 -10.999978)
				)
				(arc
					(start 136.562338 -16.202406)
					(mid 136.632611 -16.369028)
					(end 136.799828 -16.437864)
				)
				(xy 136.863074 -16.437864)
				(arc
					(start 142.80007 -16.437864)
					(mid 142.967911 -16.3685)
					(end 143.037814 -16.200882)
				)
				(arc
					(start 143.037814 -10.959846)
					(mid 143.560079 -9.747923)
					(end 144.777206 -9.237726)
				)
				(arc
					(start 166.349934 -9.237726)
					(mid 167.594147 -9.751993)
					(end 168.112186 -10.994644)
				)
				(xy 168.112186 -16.196564)
				(arc
					(start 168.112186 -16.20012)
					(mid 168.183081 -16.369483)
					(end 168.353486 -16.437864)
				)
				(xy 174.34941 -16.437864)
				(arc
					(start 174.349918 -16.43761)
					(mid 174.517473 -16.367062)
					(end 174.587662 -16.199358)
				)
				(arc
					(start 174.587662 -10.700766)
					(mid 175.145335 -9.700097)
					(end 176.19345 -9.237726)
				)
				(arc
					(start 184.00268 -9.237726)
					(mid 184.168976 -9.167276)
					(end 184.23763 -9.000236)
				)
				(arc
					(start 184.23763 0)
					(mid 184.167996 0.16811)
					(end 183.999886 0.237744)
				)
			)
		)
	)
	(zone
		(layer "B.Cu")
		(hatch none 0.5)
		(connect_pads
			(clearance 0)
		)
		(min_thickness 0.25)
		(keepout
			(tracks allowed)
			(vias allowed)
			(pads allowed)
			(copperpour allowed)
			(footprints not_allowed)
		)
		(placement
			(enabled no)
			(sheetname "")
		)
		(fill
			(thermal_gap 0.5)
			(thermal_bridge_width 0.5)
			(island_removal_mode 0)
		)
		(polygon
			(pts
				(arc
					(start 79.70012 -4.99999)
					(mid 76.700126 -1.999996)
					(end 73.699878 -4.99999)
				)
				(arc
					(start 73.699878 -4.99999)
					(mid 76.700126 -8.000238)
					(end 79.70012 -4.99999)
				)
			)
		)
	)
	(zone
		(layer "B.Cu")
		(hatch none 0.5)
		(connect_pads
			(clearance 0)
		)
		(min_thickness 0.25)
		(keepout
			(tracks allowed)
			(vias allowed)
			(pads allowed)
			(copperpour allowed)
			(footprints not_allowed)
		)
		(placement
			(enabled no)
			(sheetname "")
		)
		(fill
			(thermal_gap 0.5)
			(thermal_bridge_width 0.5)
			(island_removal_mode 0)
		)
		(polygon
			(pts
				(arc
					(start 127.124968 -4.99999)
					(mid 124.124974 -1.999996)
					(end 121.12498 -4.99999)
				)
				(arc
					(start 121.12498 -4.99999)
					(mid 124.124974 -7.999984)
					(end 127.124968 -4.99999)
				)
			)
		)
	)
	(zone
		(net "GND")
		(layer "B.Cu")
		(hatch none 0.5)
		(connect_pads
			(clearance 0.5)
		)
		(min_thickness 0.25)
		(fill yes
			(thermal_gap 0.5)
			(thermal_bridge_width 0.5)
			(island_removal_mode 0)
		)
		(polygon
			(pts
				(arc
					(start 79.937864 -10.994898)
					(mid 80.455808 -9.752078)
					(end 81.700116 -9.237726)
				)
				(arc
					(start 103.250492 -9.237726)
					(mid 104.496249 -9.753893)
					(end 105.012236 -10.999724)
				)
				(arc
					(start 105.012236 -16.188944)
					(mid 105.083906 -16.368347)
					(end 105.264204 -16.437864)
				)
				(arc
					(start 111.250984 -16.437864)
					(mid 111.41754 -16.36877)
					(end 111.487712 -16.20266)
				)
				(arc
					(start 111.487712 -10.983468)
					(mid 112.00966 -9.747999)
					(end 113.249964 -9.237726)
				)
				(xy 117.83441 -9.237726) (xy 118.063264 -9.008872) (xy 118.063264 -7.759446) (xy 116.626894 -6.323076)
				(xy 114.977418 -6.323076) (xy 114.440208 -6.323076) (xy 113.128298 -7.634986) (xy 112.24895 -7.634986)
				(xy 110.32109 -9.562846) (xy 110.32109 -14.174216) (xy 109.888274 -14.607032) (xy 106.724704 -14.607032)
				(xy 106.172 -14.054328) (xy 106.172 -10.16) (xy 103.251 -7.239) (xy 103.251 -7.112) (xy 103.251 -6.477)
				(xy 102.997 -6.223) (xy 83.185 -6.223) (xy 82.481166 -6.223) (xy 80.703166 -8.001) (xy 78.737968 -9.966198)
				(xy 78.737968 -14.182598) (xy 78.674468 -14.246098) (xy 78.49743 -14.423136) (xy 78.338172 -14.582394)
				(xy 74.918316 -14.582394) (xy 74.759058 -14.423136) (xy 74.483468 -14.147546) (xy 74.483468 -11.43381)
				(xy 74.332084 -11.282426) (xy 73.597516 -11.282426) (xy 73.462134 -11.417808) (xy 73.462134 -15.199868)
				(arc
					(start 73.462134 -16.199866)
					(mid 73.531842 -16.368156)
					(end 73.700132 -16.437864)
				)
				(arc
					(start 79.70012 -16.437864)
					(mid 79.866922 -16.366922)
					(end 79.937864 -16.20012)
				)
			)
		)
	)
	(zone
		(net "P5V_A")
		(layer "B.Cu")
		(hatch none 0.5)
		(connect_pads
			(clearance 0.5)
		)
		(min_thickness 0.25)
		(fill yes
			(thermal_gap 0.5)
			(thermal_bridge_width 0.5)
			(island_removal_mode 0)
		)
		(polygon
			(pts
				(xy 39.0906 -7.1374) (xy 41.3766 -7.1374) (xy 42.1132 -7.1374) (xy 42.3926 -6.858) (xy 42.3926 -3.81)
				(xy 41.3766 -2.794) (xy 39.8399 -2.794) (xy 34.4424 -2.794) (xy 33.9852 -3.2512) (xy 33.9852 -5.2832)
				(xy 34.0614 -5.3594) (xy 35.3822 -5.3594) (xy 35.7378 -5.0038) (xy 35.7378 -4.1402) (xy 35.7886 -4.0894)
				(xy 36.068 -3.81) (xy 38.6588 -3.81) (xy 39.0144 -4.1656) (xy 39.0144 -4.2418) (xy 39.0144 -7.0612)
			)
		)
	)
	(zone
		(net "P5V_A")
		(layer "B.Cu")
		(hatch none 0.5)
		(connect_pads
			(clearance 0.5)
		)
		(min_thickness 0.25)
		(fill yes
			(thermal_gap 0.5)
			(thermal_bridge_width 0.5)
			(island_removal_mode 0)
		)
		(polygon
			(pts
				(xy 48.3362 -14.1732) (xy 50.9524 -14.1732) (xy 51.0286 -14.2494) (xy 51.0286 -16.383) (xy 50.8762 -16.5354)
				(xy 48.4886 -16.5354) (xy 48.2854 -16.3322) (xy 48.2854 -14.224)
			)
		)
	)
	(zone
		(layer "B.Cu")
		(hatch none 0.5)
		(connect_pads
			(clearance 0)
		)
		(min_thickness 0.25)
		(keepout
			(tracks allowed)
			(vias allowed)
			(pads allowed)
			(copperpour allowed)
			(footprints not_allowed)
		)
		(placement
			(enabled no)
			(sheetname "")
		)
		(fill
			(thermal_gap 0.5)
			(thermal_bridge_width 0.5)
			(island_removal_mode 0)
		)
		(polygon
			(pts
				(xy 57.449974 0.999998) (xy 57.449974 -9.59993) (xy 40.850058 -9.59993) (xy 40.850058 0.999998)
			)
		)
	)
	(zone
		(layer "B.Cu")
		(hatch none 0.5)
		(connect_pads
			(clearance 0)
		)
		(min_thickness 0.25)
		(keepout
			(tracks not_allowed)
			(vias allowed)
			(pads allowed)
			(copperpour not_allowed)
			(footprints allowed)
		)
		(placement
			(enabled no)
			(sheetname "")
		)
		(fill
			(thermal_gap 0.5)
			(thermal_bridge_width 0.5)
			(island_removal_mode 0)
		)
		(polygon
			(pts
				(arc
					(start 127.124968 -4.99999)
					(mid 124.124974 -1.999996)
					(end 121.12498 -4.99999)
				)
				(arc
					(start 121.12498 -4.99999)
					(mid 124.124974 -7.999984)
					(end 127.124968 -4.99999)
				)
			)
		)
	)
	(zone
		(layer "B.Cu")
		(hatch none 0.5)
		(connect_pads
			(clearance 0)
		)
		(min_thickness 0.25)
		(keepout
			(tracks allowed)
			(vias allowed)
			(pads allowed)
			(copperpour allowed)
			(footprints not_allowed)
		)
		(placement
			(enabled no)
			(sheetname "")
		)
		(fill
			(thermal_gap 0.5)
			(thermal_bridge_width 0.5)
			(island_removal_mode 0)
		)
		(polygon
			(pts
				(arc
					(start 171.425108 -4.99999)
					(mid 172.875194 -6.450076)
					(end 174.325026 -4.99999)
				)
				(arc
					(start 174.325026 -4.99999)
					(mid 172.875194 -3.550158)
					(end 171.425108 -4.99999)
				)
			)
		)
	)
)
